# Altium SchDoc records: GPS_IMU_SENSORS.SchDoc
|HEADER=Protel for Windows - Schematic Capture Binary File Version 5.0|Weight=818|MinorVersion=2
|RECORD=31|FontIdCount=8|Size1=10|FontName1=Times New Roman|Size2=10|Underline2=T|FontName2=Times New Roman|Size3=12|FontName3=Arial|Size4=14|FontName4=Arial|Size5=24|FontName5=Times New Roman|Size6=8|FontName6=Arial|Size7=10|FontName7=Arial|Size8=12|Underline8=T|FontName8=Arial|UseMBCS=T|IsBOC=T|HotSpotGridOn=T|HotSpotGridSize=4|SheetStyle=12|SystemFont=7|BorderOn=T|SheetNumberSpaceSize=12|AreaColor=16317695|SnapGridOn=T|SnapGridSize=10|VisibleGridOn=T|VisibleGridSize=10|CustomX=2338|CustomX_Frac=58268|CustomY=1653|CustomY_Frac=54331|CustomXZones=8|CustomYZones=6|CustomMarginWidth=19|CustomMarginWidth_Frac=80000|ShowTemplateGraphics=T|TemplateFileName=C:\Users\<user>\Documents\Altium\AD20\Templates\Timecard.SchDot|Display_Unit=0
|RECORD=39|IsNotAccesible=T|OwnerPartId=-1|FileName=C:\Users\<user>\Documents\Altium\AD20\Templates\Timecard.SchDot
|RECORD=4|OwnerIndex=1|OwnerPartId=-1|Location.X=1594|Location.Y=39|Color=8388608|FontID=8|Text=timingcard.com|URL=http://timingcard.com
|RECORD=6|OwnerIndex=1|IndexInSheet=1|OwnerPartId=-1|LocationCount=2|X1=1680|Y1=35|X2=1576|Y2=35
|RECORD=4|OwnerIndex=1|IndexInSheet=2|OwnerPartId=-1|Location.X=1614|Location.X_Frac=42446|Location.Y=19|Location.Y_Frac=96838|FontID=3|Text==SheetNumber
|RECORD=4|OwnerIndex=1|IndexInSheet=3|OwnerPartId=-1|Location.X=1581|Location.X_Frac=42446|Location.Y=29|Location.Y_Frac=96838|Justification=3|FontID=6|Text=SHEET
|RECORD=4|OwnerIndex=1|IndexInSheet=4|OwnerPartId=-1|Location.X=1639|Location.X_Frac=42446|Location.Y=29|Location.Y_Frac=96838|Justification=3|FontID=6|Text=OF
|RECORD=6|OwnerIndex=1|IndexInSheet=5|OwnerPartId=-1|LineWidth=1|LocationCount=2|X1=1679|X1_Frac=42446|Y1=105|Y1_Frac=96838|X2=1576|Y2=106
|RECORD=4|OwnerIndex=1|IndexInSheet=6|OwnerPartId=-1|Location.X=1658|Location.Y=20|FontID=3|Text==SheetTotal
|RECORD=30|OwnerIndex=1|IndexInSheet=7|OwnerPartId=-1|Location.X=1578|Location.Y=53|Corner.X=1673|Corner.X_Frac=88801|Corner.Y=103|KeepAspect=T|FileName=C:\Users\<user>\Desktop\Timecard Logo\TIMECARD.jpg
|RECORD=6|OwnerIndex=1|IndexInSheet=8|OwnerPartId=-1|LineWidth=1|LocationCount=2|X1=1576|X1_Frac=3162|Y1=105|Y1_Frac=42446|X2=1576|Y2=20
|RECORD=6|OwnerIndex=1|IndexInSheet=9|OwnerPartId=-1|LocationCount=2|X1=1680|Y1=51|X2=1576|Y2=51
|RECORD=41|IndexInSheet=1|OwnerPartId=-1|Color=8388608|FontID=1|IsHidden=T|Text=*|Name=CurrentTime|ReadOnlyState=1
|RECORD=41|IndexInSheet=2|OwnerPartId=-1|Color=8388608|FontID=1|IsHidden=T|Text=*|Name=CurrentDate|ReadOnlyState=1
|RECORD=41|IndexInSheet=3|OwnerPartId=-1|Color=8388608|FontID=1|IsHidden=T|Text=*|Name=Time|ReadOnlyState=1
|RECORD=41|IndexInSheet=4|OwnerPartId=-1|Color=8388608|FontID=1|IsHidden=T|Text=*|Name=Date|ReadOnlyState=1
|RECORD=41|IndexInSheet=5|OwnerPartId=-1|Color=8388608|FontID=1|IsHidden=T|Text=*|Name=DocumentFullPathAndName|ReadOnlyState=1
|RECORD=41|IndexInSheet=6|OwnerPartId=-1|Color=8388608|FontID=1|IsHidden=T|Text=*|Name=DocumentName|ReadOnlyState=1
|RECORD=41|IndexInSheet=7|OwnerPartId=-1|Color=8388608|FontID=1|IsHidden=T|Text=*|Name=ModifiedDate|ReadOnlyState=1
|RECORD=41|IndexInSheet=8|OwnerPartId=-1|Color=8388608|FontID=1|IsHidden=T|Text=*|Name=ApprovedBy|ReadOnlyState=1
|RECORD=41|IndexInSheet=9|OwnerPartId=-1|Color=8388608|FontID=1|IsHidden=T|Text=*|Name=CheckedBy|ReadOnlyState=1
|RECORD=41|IndexInSheet=10|OwnerPartId=-1|Color=8388608|FontID=1|IsHidden=T|Text=<name>|Name=Author|ReadOnlyState=1
|RECORD=41|IndexInSheet=11|OwnerPartId=-1|Color=8388608|FontID=1|IsHidden=T|Text=*|Name=CompanyName|ReadOnlyState=1
|RECORD=41|IndexInSheet=12|OwnerPartId=-1|Color=8388608|FontID=1|IsHidden=T|Text=*|Name=DrawnBy|ReadOnlyState=1
|RECORD=41|IndexInSheet=13|OwnerPartId=-1|Color=8388608|FontID=1|IsHidden=T|Text=*|Name=Engineer|ReadOnlyState=1
|RECORD=41|IndexInSheet=14|OwnerPartId=-1|Color=8388608|FontID=1|IsHidden=T|Text=*|Name=Organization|ReadOnlyState=1
|RECORD=41|IndexInSheet=15|OwnerPartId=-1|Color=8388608|FontID=1|IsHidden=T|Text=*|Name=Address1|ReadOnlyState=1
|RECORD=41|IndexInSheet=16|OwnerPartId=-1|Color=8388608|FontID=1|IsHidden=T|Text=*|Name=Address2|ReadOnlyState=1
|RECORD=41|IndexInSheet=17|OwnerPartId=-1|Color=8388608|FontID=1|IsHidden=T|Text=*|Name=Address3|ReadOnlyState=1
|RECORD=41|IndexInSheet=18|OwnerPartId=-1|Color=8388608|FontID=1|IsHidden=T|Text=*|Name=Address4|ReadOnlyState=1
|RECORD=41|IndexInSheet=19|OwnerPartId=-1|Color=8388608|FontID=1|IsHidden=T|Text=Gransmaster GPS & IMU|Name=Title|ReadOnlyState=1
|RECORD=41|IndexInSheet=20|OwnerPartId=-1|Color=8388608|FontID=1|IsHidden=T|Text=*|Name=DocumentNumber|ReadOnlyState=1
|RECORD=41|IndexInSheet=21|OwnerPartId=-1|Color=8388608|FontID=1|IsHidden=T|Text=A|Name=Revision|ReadOnlyState=1
|RECORD=41|IndexInSheet=22|OwnerPartId=-1|Color=8388608|FontID=1|IsHidden=T|Text=5|Name=SheetNumber|ReadOnlyState=1
|RECORD=41|IndexInSheet=23|OwnerPartId=-1|Color=8388608|FontID=1|IsHidden=T|Text=7|Name=SheetTotal|ReadOnlyState=1
|RECORD=41|IndexInSheet=24|OwnerPartId=-1|Color=8388608|FontID=1|IsHidden=T|Text=*|Name=Rule|ReadOnlyState=1
|RECORD=41|IndexInSheet=25|OwnerPartId=-1|Color=8388608|FontID=1|IsHidden=T|Text=*|Name=ImagePath|ReadOnlyState=1
|RECORD=41|IndexInSheet=26|OwnerPartId=-1|Color=8388608|FontID=1|IsHidden=T|Text=*|Name=ProjectName|ReadOnlyState=1
|RECORD=41|IndexInSheet=27|OwnerPartId=-1|Color=8388608|FontID=1|IsHidden=T|Text=*|Name=Application_BuildNumber|ReadOnlyState=1
|RECORD=41|IndexInSheet=28|OwnerPartId=-1|Location.X=21474|Location.X_Frac=83647|Location.Y=21464|Location.Y_Frac=83647|Color=8388608|FontID=1|IsHidden=T|Text=01910|Name=Customer
|RECORD=41|IndexInSheet=29|OwnerPartId=-1|Location.X=1000|Location.Y=10|Color=8388608|FontID=1|IsHidden=T|Text=*|Name=DocStatus
|RECORD=17|IndexInSheet=30|OwnerPartId=-1|ShowNetName=T|Location.X=320|Location.Y=840|Orientation=1|Color=128|FontID=1|Text=+5.0V
|RECORD=17|IndexInSheet=31|OwnerPartId=-1|Style=4|ShowNetName=T|Location.X=740|Location.Y=750|Orientation=3|Color=128|FontID=1|Text=GND
|RECORD=17|IndexInSheet=32|OwnerPartId=-1|ShowNetName=T|Location.X=220|Location.Y=840|Orientation=1|Color=128|FontID=1|Text=+3.3V
|RECORD=17|IndexInSheet=33|OwnerPartId=-1|Style=4|ShowNetName=T|Location.X=220|Location.Y=760|Orientation=3|Color=128|FontID=1|Text=GND
|RECORD=17|IndexInSheet=34|OwnerPartId=-1|Style=4|ShowNetName=T|Location.X=320|Location.Y=760|Orientation=3|Color=128|FontID=1|Text=GND
|RECORD=17|IndexInSheet=35|OwnerPartId=-1|ShowNetName=T|Location.X=810|Location.Y=810|Color=255|FontID=1|Text=GPS1_TP2|IsCrossSheetConnector=T
|RECORD=17|IndexInSheet=36|OwnerPartId=-1|ShowNetName=T|Location.X=810|Location.Y=800|Color=255|FontID=1|Text=GPS1_TP1|IsCrossSheetConnector=T
|RECORD=17|IndexInSheet=37|OwnerPartId=-1|ShowNetName=T|Location.X=810|Location.Y=790|Color=255|FontID=1|Text=GPS1_RX|IsCrossSheetConnector=T
|RECORD=17|IndexInSheet=38|OwnerPartId=-1|ShowNetName=T|Location.X=470|Location.Y=800|Orientation=2|Color=255|FontID=1|Text=GPS1_TX|IsCrossSheetConnector=T
|RECORD=17|IndexInSheet=39|OwnerPartId=-1|ShowNetName=T|Location.X=470|Location.Y=790|Orientation=2|Color=255|FontID=1|Text=GPS1_RST|IsCrossSheetConnector=T
|RECORD=4|IndexInSheet=40|OwnerPartId=-1|Location.X=620|Location.Y=890|Color=8388608|FontID=5|Text=GPS
|RECORD=1|LibReference=CAP_0805_10UF_25V|ComponentDescription=CAP, CER, 10.UF, 25V, 10%, X5R, 0805|PartCount=2|DisplayModeCount=1|IndexInSheet=41|OwnerPartId=-1|Location.X=200|Location.Y=750|CurrentPartId=1|LibraryPath=*|SourceLibraryName=Capacitors.IntLib|TargetFileName=*|AreaColor=11599871|Color=128|PartIDLocked=F|DesignItemId=CAP_0805_10UF_25V|AllPinCount=2
|RECORD=41|OwnerIndex=52|OwnerPartId=-1|Location.X=200|Location.Y=750|Color=8388608|FontID=3|IsHidden=T|Text=TAIYO YUDEN|Name=MFG NAME
|RECORD=41|OwnerIndex=52|IndexInSheet=1|OwnerPartId=-1|Location.X=200|Location.Y=750|Color=8388608|FontID=3|IsHidden=T|Text=TMK212BBJ106KG-T|Name=MFG PART NUM
|RECORD=41|OwnerIndex=52|IndexInSheet=2|OwnerPartId=-1|Location.X=200|Location.Y=750|Color=8388608|FontID=3|IsHidden=T|Text=10/23/2013|Name=MODIFY DATE
|RECORD=41|OwnerIndex=52|IndexInSheet=3|OwnerPartId=-1|Location.X=200|Location.Y=750|Color=8388608|FontID=3|IsHidden=T|Text=CAP, CER|Name=CATEGORY
|RECORD=41|OwnerIndex=52|IndexInSheet=4|OwnerPartId=-1|Location.X=198|Location.Y=762|Location.Y_Frac=50000|Color=8388608|FontID=3|IsHidden=T|Text=4/11/2006 3:37:28 PM|Name=Date
|RECORD=41|OwnerIndex=52|IndexInSheet=5|OwnerPartId=-1|Location.X=206|Location.Y=824|Location.Y_Frac=48252|Color=8388608|FontID=3|IsHidden=T|Text=*|Name=SHEETPART
|RECORD=41|OwnerIndex=52|IndexInSheet=6|OwnerPartId=-1|Location.X=206|Location.Y=824|Location.Y_Frac=48252|Color=8388608|FontID=3|IsHidden=T|Text=10%|Name=P1
|RECORD=41|OwnerIndex=52|IndexInSheet=7|OwnerPartId=-1|Location.X=206|Location.Y=824|Location.Y_Frac=48252|Color=8388608|FontID=3|IsHidden=T|Text=85C|Name=MAXTEMP
|RECORD=41|OwnerIndex=52|IndexInSheet=8|OwnerPartId=-1|Location.X=206|Location.Y=824|Location.Y_Frac=48252|Color=8388608|FontID=3|IsHidden=T|Text=-55C|Name=MINTEMP
|RECORD=41|OwnerIndex=52|IndexInSheet=9|OwnerPartId=-1|Location.X=206|Location.Y=824|Location.Y_Frac=48252|Color=8388608|FontID=3|IsHidden=T|Name=OTHER
|RECORD=41|OwnerIndex=52|IndexInSheet=10|OwnerPartId=-1|Location.X=206|Location.Y=824|Location.Y_Frac=48252|Color=8388608|FontID=3|IsHidden=T|Text=25V|Name=P2
|RECORD=41|OwnerIndex=52|IndexInSheet=11|OwnerPartId=-1|Location.X=206|Location.Y=824|Location.Y_Frac=48252|Color=8388608|FontID=3|IsHidden=T|Text=X5R|Name=P3
|RECORD=41|OwnerIndex=52|IndexInSheet=12|OwnerPartId=-1|Location.X=206|Location.Y=824|Location.Y_Frac=48252|Color=8388608|FontID=3|IsHidden=T|Text=0805|Name=Size
|RECORD=41|OwnerIndex=52|IndexInSheet=13|OwnerPartId=-1|Location.X=206|Location.Y=824|Location.Y_Frac=48252|Color=8388608|FontID=3|IsHidden=T|Name=SUB
|RECORD=41|OwnerIndex=52|IndexInSheet=14|OwnerPartId=-1|Location.X=206|Location.Y=824|Location.Y_Frac=48252|Color=8388608|FontID=1|IsHidden=T|Text=CAP, CER, 10.UF, 10V, 10%, X5R, 0805|Name=DESC
|RECORD=41|OwnerIndex=52|IndexInSheet=15|OwnerPartId=-1|Location.X=206|Location.Y=823|Location.Y_Frac=98252|Color=8388608|FontID=1|IsHidden=T|Text=MOUSER|Name=Supplier 1|ReadOnlyState=1
|RECORD=41|OwnerIndex=52|IndexInSheet=16|OwnerPartId=-1|Location.X=206|Location.Y=823|Location.Y_Frac=98252|Color=8388608|FontID=1|IsHidden=T|Text=963-TMK212BBJ106KG-T|Name=Supplier Part Number 1|ReadOnlyState=1
|RECORD=41|OwnerIndex=52|IndexInSheet=17|OwnerPartId=-1|Location.X=230|Location.Y=780|Color=8388608|FontID=3|Text=10uF|Name=VALUE
|RECORD=2|OwnerIndex=52|OwnerPartId=1|FormalType=1|Electrical=4|PinConglomerate=35|PinLength=10|Location.X=220|Location.Y=780|Name=2|Designator=2|SwapIdPin=2|SwapIDPart=1|PinPropagationDelay=0.000000E+000
|RECORD=2|OwnerIndex=52|OwnerPartId=1|FormalType=1|Electrical=4|PinConglomerate=33|PinLength=10|Location.X=220|Location.Y=790|Name=1|Designator=1|SwapIdPin=1|SwapIDPart=1|PinPropagationDelay=0.000000E+000
|RECORD=13|OwnerIndex=52|IsNotAccesible=T|IndexInSheet=20|OwnerPartId=1|Location.X=220|Location.Y=782|Location.Y_Frac=50000|Corner.X=220|Corner.Y=780|LineWidth=1|Color=16711680
|RECORD=13|OwnerIndex=52|IsNotAccesible=T|IndexInSheet=21|OwnerPartId=1|Location.X=220|Location.Y=790|Corner.X=220|Corner.Y=787|Corner.Y_Frac=50000|LineWidth=1|Color=16711680
|RECORD=13|OwnerIndex=52|IsNotAccesible=T|IndexInSheet=22|OwnerPartId=1|Location.X=225|Location.Y=782|Location.Y_Frac=50000|Corner.X=215|Corner.Y=782|Corner.Y_Frac=50000|LineWidth=1|Color=16711680
|RECORD=13|OwnerIndex=52|IsNotAccesible=T|IndexInSheet=23|OwnerPartId=1|Location.X=225|Location.Y=787|Location.Y_Frac=50000|Corner.X=215|Corner.Y=787|Corner.Y_Frac=50000|LineWidth=1|Color=16711680
|RECORD=41|OwnerIndex=52|IndexInSheet=24|OwnerPartId=-1|Location.X=206|Location.Y=823|Location.Y_Frac=98951|Color=8388608|FontID=1|IsHidden=T|Text=<VALENTIUM>|Name=VALENTIUM PART NUM
|RECORD=34|OwnerIndex=52|IndexInSheet=-1|OwnerPartId=-1|Location.X=230|Location.Y=790|Color=8388608|FontID=4|Text=C58|Name=Designator|ReadOnlyState=1
|RECORD=41|OwnerIndex=52|IndexInSheet=-1|OwnerPartId=-1|Location.X=227|Location.X_Frac=50000|Location.Y=745|Color=8388608|FontID=3|IsHidden=T|Text=CAP_0805_10UF_25V|Name=Comment
|RECORD=44|OwnerIndex=52
|RECORD=45|OwnerIndex=82|IndexInSheet=-1|Description=Chip Capacitor, 0805, 2-Leads, Body 2.00x1.25mm, IPC Medium Density|UseComponentLibrary=T|ModelName=CAPC2012X14N|ModelType=PCBLIB|DatafileCount=1|ModelDatafileEntity0=CAPC2012X14N|ModelDatafileKind0=PCBLib|IsCurrent=T|DatalinksLocked=T|DatabaseDatalinksLocked=T|IntegratedModel=T|DatabaseModel=T
|RECORD=46|OwnerIndex=83
|RECORD=48|OwnerIndex=83
|RECORD=1|LibReference=CAP_0805_10UF_25V|ComponentDescription=CAP, CER, 10.UF, 25V, 10%, X5R, 0805|PartCount=2|DisplayModeCount=1|IndexInSheet=42|OwnerPartId=-1|Location.X=300|Location.Y=750|CurrentPartId=1|LibraryPath=*|SourceLibraryName=Capacitors.IntLib|TargetFileName=*|AreaColor=11599871|Color=128|PartIDLocked=F|DesignItemId=CAP_0805_10UF_25V|AllPinCount=2
|RECORD=41|OwnerIndex=86|OwnerPartId=-1|Location.X=300|Location.Y=750|Color=8388608|FontID=3|IsHidden=T|Text=TAIYO YUDEN|Name=MFG NAME
|RECORD=41|OwnerIndex=86|IndexInSheet=1|OwnerPartId=-1|Location.X=300|Location.Y=750|Color=8388608|FontID=3|IsHidden=T|Text=TMK212BBJ106KG-T|Name=MFG PART NUM
|RECORD=41|OwnerIndex=86|IndexInSheet=2|OwnerPartId=-1|Location.X=300|Location.Y=750|Color=8388608|FontID=3|IsHidden=T|Text=10/23/2013|Name=MODIFY DATE
|RECORD=41|OwnerIndex=86|IndexInSheet=3|OwnerPartId=-1|Location.X=300|Location.Y=750|Color=8388608|FontID=3|IsHidden=T|Text=CAP, CER|Name=CATEGORY
|RECORD=41|OwnerIndex=86|IndexInSheet=4|OwnerPartId=-1|Location.X=298|Location.Y=762|Location.Y_Frac=50000|Color=8388608|FontID=3|IsHidden=T|Text=4/11/2006 3:37:28 PM|Name=Date
|RECORD=41|OwnerIndex=86|IndexInSheet=5|OwnerPartId=-1|Location.X=306|Location.Y=824|Location.Y_Frac=48252|Color=8388608|FontID=3|IsHidden=T|Text=*|Name=SHEETPART
|RECORD=41|OwnerIndex=86|IndexInSheet=6|OwnerPartId=-1|Location.X=306|Location.Y=824|Location.Y_Frac=48252|Color=8388608|FontID=3|IsHidden=T|Text=10%|Name=P1
|RECORD=41|OwnerIndex=86|IndexInSheet=7|OwnerPartId=-1|Location.X=306|Location.Y=824|Location.Y_Frac=48252|Color=8388608|FontID=3|IsHidden=T|Text=85C|Name=MAXTEMP
|RECORD=41|OwnerIndex=86|IndexInSheet=8|OwnerPartId=-1|Location.X=306|Location.Y=824|Location.Y_Frac=48252|Color=8388608|FontID=3|IsHidden=T|Text=-55C|Name=MINTEMP
|RECORD=41|OwnerIndex=86|IndexInSheet=9|OwnerPartId=-1|Location.X=306|Location.Y=824|Location.Y_Frac=48252|Color=8388608|FontID=3|IsHidden=T|Name=OTHER
|RECORD=41|OwnerIndex=86|IndexInSheet=10|OwnerPartId=-1|Location.X=306|Location.Y=824|Location.Y_Frac=48252|Color=8388608|FontID=3|IsHidden=T|Text=25V|Name=P2
|RECORD=41|OwnerIndex=86|IndexInSheet=11|OwnerPartId=-1|Location.X=306|Location.Y=824|Location.Y_Frac=48252|Color=8388608|FontID=3|IsHidden=T|Text=X5R|Name=P3
|RECORD=41|OwnerIndex=86|IndexInSheet=12|OwnerPartId=-1|Location.X=306|Location.Y=824|Location.Y_Frac=48252|Color=8388608|FontID=3|IsHidden=T|Text=0805|Name=Size
|RECORD=41|OwnerIndex=86|IndexInSheet=13|OwnerPartId=-1|Location.X=306|Location.Y=824|Location.Y_Frac=48252|Color=8388608|FontID=3|IsHidden=T|Name=SUB
|RECORD=41|OwnerIndex=86|IndexInSheet=14|OwnerPartId=-1|Location.X=306|Location.Y=824|Location.Y_Frac=48252|Color=8388608|FontID=1|IsHidden=T|Text=CAP, CER, 10.UF, 10V, 10%, X5R, 0805|Name=DESC
|RECORD=41|OwnerIndex=86|IndexInSheet=15|OwnerPartId=-1|Location.X=306|Location.Y=823|Location.Y_Frac=98252|Color=8388608|FontID=1|IsHidden=T|Text=MOUSER|Name=Supplier 1|ReadOnlyState=1
|RECORD=41|OwnerIndex=86|IndexInSheet=16|OwnerPartId=-1|Location.X=306|Location.Y=823|Location.Y_Frac=98252|Color=8388608|FontID=1|IsHidden=T|Text=963-TMK212BBJ106KG-T|Name=Supplier Part Number 1|ReadOnlyState=1
|RECORD=41|OwnerIndex=86|IndexInSheet=17|OwnerPartId=-1|Location.X=330|Location.Y=780|Color=8388608|FontID=3|Text=10uF|Name=VALUE
|RECORD=2|OwnerIndex=86|OwnerPartId=1|FormalType=1|Electrical=4|PinConglomerate=35|PinLength=10|Location.X=320|Location.Y=780|Name=2|Designator=2|SwapIdPin=2|SwapIDPart=1|PinPropagationDelay=0.000000E+000
|RECORD=2|OwnerIndex=86|OwnerPartId=1|FormalType=1|Electrical=4|PinConglomerate=33|PinLength=10|Location.X=320|Location.Y=790|Name=1|Designator=1|SwapIdPin=1|SwapIDPart=1|PinPropagationDelay=0.000000E+000
|RECORD=13|OwnerIndex=86|IsNotAccesible=T|IndexInSheet=20|OwnerPartId=1|Location.X=320|Location.Y=782|Location.Y_Frac=50000|Corner.X=320|Corner.Y=780|LineWidth=1|Color=16711680
|RECORD=13|OwnerIndex=86|IsNotAccesible=T|IndexInSheet=21|OwnerPartId=1|Location.X=320|Location.Y=790|Corner.X=320|Corner.Y=787|Corner.Y_Frac=50000|LineWidth=1|Color=16711680
|RECORD=13|OwnerIndex=86|IsNotAccesible=T|IndexInSheet=22|OwnerPartId=1|Location.X=325|Location.Y=782|Location.Y_Frac=50000|Corner.X=315|Corner.Y=782|Corner.Y_Frac=50000|LineWidth=1|Color=16711680
|RECORD=13|OwnerIndex=86|IsNotAccesible=T|IndexInSheet=23|OwnerPartId=1|Location.X=325|Location.Y=787|Location.Y_Frac=50000|Corner.X=315|Corner.Y=787|Corner.Y_Frac=50000|LineWidth=1|Color=16711680
|RECORD=41|OwnerIndex=86|IndexInSheet=24|OwnerPartId=-1|Location.X=306|Location.Y=823|Location.Y_Frac=98951|Color=8388608|FontID=1|IsHidden=T|Text=<VALENTIUM>|Name=VALENTIUM PART NUM
|RECORD=34|OwnerIndex=86|IndexInSheet=-1|OwnerPartId=-1|Location.X=330|Location.Y=790|Color=8388608|FontID=4|Text=C60|Name=Designator|ReadOnlyState=1
|RECORD=41|OwnerIndex=86|IndexInSheet=-1|OwnerPartId=-1|Location.X=327|Location.X_Frac=50000|Location.Y=745|Color=8388608|FontID=3|IsHidden=T|Text=CAP_0805_10UF_25V|Name=Comment
|RECORD=44|OwnerIndex=86
|RECORD=45|OwnerIndex=116|IndexInSheet=-1|Description=Chip Capacitor, 0805, 2-Leads, Body 2.00x1.25mm, IPC Medium Density|UseComponentLibrary=T|ModelName=CAPC2012X14N|ModelType=PCBLIB|DatafileCount=1|ModelDatafileEntity0=CAPC2012X14N|ModelDatafileKind0=PCBLib|IsCurrent=T|DatalinksLocked=T|DatabaseDatalinksLocked=T|IntegratedModel=T|DatabaseModel=T
|RECORD=46|OwnerIndex=117
|RECORD=48|OwnerIndex=117
|RECORD=1|LibReference=RCB-F9T|ComponentDescription=MOD, GPS|PartCount=2|DisplayModeCount=1|IndexInSheet=43|OwnerPartId=-1|Location.X=640|Location.Y=810|CurrentPartId=1|LibraryPath=*|SourceLibraryName=Modules.IntLib|TargetFileName=*|AreaColor=11599871|Color=128|PartIDLocked=F|PinsMoveable=T|DesignItemId=RCB-F9T|AllPinCount=8
|RECORD=41|OwnerIndex=120|OwnerPartId=-1|Location.X=640|Location.Y=810|Color=8388608|FontID=3|IsHidden=T|Text=RCB-F9T|Name=MFG PART NUM
|RECORD=41|OwnerIndex=120|IndexInSheet=1|OwnerPartId=-1|Location.X=640|Location.Y=810|Color=8388608|FontID=3|IsHidden=T|Text=UBLOCKS|Name=MFG NAME
|RECORD=41|OwnerIndex=120|IndexInSheet=2|OwnerPartId=-1|Location.X=640|Location.Y=810|Color=8388608|FontID=3|IsHidden=T|Text=MOD|Name=CATEGORY
|RECORD=41|OwnerIndex=120|IndexInSheet=3|OwnerPartId=-1|Location.X=640|Location.Y=810|Color=8388608|FontID=3|IsHidden=T|Text=9/11/13|Name=MODIFY DATE
|RECORD=41|OwnerIndex=120|IndexInSheet=4|OwnerPartId=-1|Location.X=638|Location.Y=559|Color=8388608|FontID=1|IsHidden=T|Text=GPS|Name=P1
|RECORD=41|OwnerIndex=120|IndexInSheet=5|OwnerPartId=-1|Location.X=638|Location.Y=559|Color=8388608|FontID=1|IsHidden=T|Name=P2
|RECORD=41|OwnerIndex=120|IndexInSheet=6|OwnerPartId=-1|Location.X=638|Location.Y=559|Color=8388608|FontID=1|IsHidden=T|Name=P3
|RECORD=41|OwnerIndex=120|IndexInSheet=7|OwnerPartId=-1|Location.X=638|Location.Y=559|Color=8388608|FontID=1|IsHidden=T|Name=OTHER
|RECORD=41|OwnerIndex=120|IndexInSheet=8|OwnerPartId=-1|Location.X=638|Location.Y=559|Color=8388608|FontID=1|IsHidden=T|Name=DATE
|RECORD=41|OwnerIndex=120|IndexInSheet=9|OwnerPartId=-1|Location.X=638|Location.Y=559|Color=8388608|FontID=1|IsHidden=T|Text=*|Name=SHEETPART
|RECORD=41|OwnerIndex=120|IndexInSheet=10|OwnerPartId=-1|Location.X=638|Location.Y=559|Color=8388608|FontID=1|IsHidden=T|Name=SUB
|RECORD=41|OwnerIndex=120|IndexInSheet=11|OwnerPartId=-1|Location.X=638|Location.Y=559|Color=8388608|FontID=1|IsHidden=T|Name=SIZE
|RECORD=41|OwnerIndex=120|IndexInSheet=12|OwnerPartId=-1|Location.X=638|Location.Y=559|Color=8388608|FontID=1|IsHidden=T|Text=-40C|Name=MINTEMP
|RECORD=41|OwnerIndex=120|IndexInSheet=13|OwnerPartId=-1|Location.X=638|Location.Y=559|Color=8388608|FontID=1|IsHidden=T|Text=80C|Name=MAXTEMP
|RECORD=41|OwnerIndex=120|IndexInSheet=14|OwnerPartId=-1|Location.X=638|Location.Y=549|Color=8388608|FontID=1|IsHidden=T|Text=.|Name=DATE
|RECORD=41|OwnerIndex=120|IndexInSheet=15|OwnerPartId=-1|Location.X=638|Location.Y=864|Color=8388608|FontID=1|IsHidden=T|Text=MOD BLE 4.2|Name=DESC
|RECORD=41|OwnerIndex=120|IndexInSheet=16|OwnerPartId=-1|Location.X=608|Location.Y=882|Color=8388608|FontID=1|IsHidden=T|Text=<V PART NUM>|Name=VELENTIUM PART NUM
|RECORD=41|OwnerIndex=120|IndexInSheet=17|OwnerPartId=-1|Location.X=558|Location.Y=864|Color=8388608|FontID=1|IsHidden=T|Text=Digi-Key|Name=Supplier 1|ReadOnlyState=3
|RECORD=41|OwnerIndex=120|IndexInSheet=18|OwnerPartId=-1|Location.X=558|Location.Y=864|Color=8388608|FontID=1|IsHidden=T|Text=672-RCB-F9T-ND|Name=Supplier Part Number 1|ReadOnlyState=3
|RECORD=14|OwnerIndex=120|IsNotAccesible=T|IndexInSheet=19|OwnerPartId=1|Location.X=590|Location.Y=780|Corner.X=690|Corner.Y=830|Color=128|AreaColor=11599871|IsSolid=T
|RECORD=2|OwnerIndex=120|OwnerPartId=1|FormalType=1|Electrical=4|PinConglomerate=26|PinLength=30|Location.X=590|Location.Y=820|Name=VCC_ANT|Designator=1|SwapIDPart=Ž&Ž||PinPropagationDelay=0.000000E+000
|RECORD=2|OwnerIndex=120|OwnerPartId=1|FormalType=1|Electrical=4|PinConglomerate=26|PinLength=30|Location.X=590|Location.Y=810|Name=VCC|Designator=2|SwapIDPart=Ž&Ž||PinPropagationDelay=0.000000E+000
|RECORD=2|OwnerIndex=120|OwnerPartId=1|FormalType=1|Electrical=4|PinConglomerate=26|PinLength=30|Location.X=590|Location.Y=800|Name=TXD|Designator=3|SwapIDPart=Ž&Ž||PinPropagationDelay=0.000000E+000
|RECORD=2|OwnerIndex=120|OwnerPartId=1|FormalType=1|Electrical=4|PinConglomerate=26|PinLength=30|Location.X=590|Location.Y=790|Name=RST|Designator=4|SwapIDPart=Ž&Ž||PinPropagationDelay=0.000000E+000
|RECORD=2|OwnerIndex=120|OwnerPartId=1|FormalType=1|Electrical=4|PinConglomerate=24|PinLength=30|Location.X=690|Location.Y=790|Name=RXD|Designator=5|SwapIDPart=Ž&Ž||PinPropagationDelay=0.000000E+000
|RECORD=2|OwnerIndex=120|OwnerPartId=1|FormalType=1|Electrical=4|PinConglomerate=24|PinLength=30|Location.X=690|Location.Y=800|Name=TP1|Designator=6|SwapIDPart=Ž&Ž||PinPropagationDelay=0.000000E+000
|RECORD=2|OwnerIndex=120|OwnerPartId=1|FormalType=1|Electrical=4|PinConglomerate=24|PinLength=30|Location.X=690|Location.Y=810|Name=TP2|Designator=7|SwapIDPart=Ž&Ž||PinPropagationDelay=0.000000E+000
|RECORD=2|OwnerIndex=120|OwnerPartId=1|FormalType=1|Electrical=4|PinConglomerate=24|PinLength=30|Location.X=690|Location.Y=820|Name=GND|Designator=8|SwapIDPart=Ž&Ž||PinPropagationDelay=0.000000E+000
|RECORD=34|OwnerIndex=120|IndexInSheet=-1|OwnerPartId=-1|Location.X=590|Location.Y=830|Color=8388608|FontID=4|Text=U9|Name=Designator|ReadOnlyState=1
|RECORD=41|OwnerIndex=120|IndexInSheet=-1|OwnerPartId=-1|Location.X=590|Location.Y=768|Color=8388608|FontID=3|Text=RCB-F9T|Name=Comment
|RECORD=44|OwnerIndex=120
|RECORD=45|OwnerIndex=159|IndexInSheet=-1|ModelName=GNSS|ModelType=PCBLIB|DatafileCount=1|ModelDatafileEntity0=GNSS|ModelDatafileKind0=PCBLib|IsCurrent=T|IntegratedModel=T|DatabaseModel=T
|RECORD=46|OwnerIndex=160
|RECORD=48|OwnerIndex=160
|RECORD=1|LibReference=93fe34f5f049140596bab6421a6454b|ComponentDescription=IC EEPROM 2K I2C 1MHZ SOT23-5|PartCount=2|DisplayModeCount=1|IndexInSheet=44|OwnerPartId=-1|Location.X=1200|Location.Y=840|CurrentPartId=1|LibraryPath=*|SourceLibraryName=Altium Content Vault|TargetFileName=*|AreaColor=11599871|Color=128|PartIDLocked=T|DesignItemId=CMP-06313-000011-1|AllPinCount=5
|RECORD=14|OwnerIndex=163|IsNotAccesible=T|OwnerPartId=1|Location.X=1220|Location.Y=790|Corner.X=1290|Corner.Y=850|LineWidth=1|Color=128|AreaColor=11599871|IsSolid=T
|RECORD=2|OwnerIndex=163|OwnerPartId=1|Electrical=7|PinConglomerate=58|PinLength=20|Location.X=1220|Location.Y=840|Name=VCC|Designator=4|PinPropagationDelay=0.000000E+000
|RECORD=2|OwnerIndex=163|OwnerPartId=1|SymBol_InnerEdge=3|PinConglomerate=56|PinLength=20|Location.X=1290|Location.Y=840|Name=SCL|Designator=1|PinPropagationDelay=0.000000E+000
|RECORD=2|OwnerIndex=163|OwnerPartId=1|Electrical=1|PinConglomerate=56|PinLength=20|Location.X=1290|Location.Y=830|Name=SDA|Designator=3|PinPropagationDelay=0.000000E+000
|RECORD=2|OwnerIndex=163|OwnerPartId=1|PinConglomerate=58|PinLength=20|Location.X=1220|Location.Y=800|Name=WP|Designator=5|PinPropagationDelay=0.000000E+000
|RECORD=2|OwnerIndex=163|OwnerPartId=1|Electrical=7|PinConglomerate=56|PinLength=20|Location.X=1290|Location.Y=800|Name=GND|Designator=2|PinPropagationDelay=0.000000E+000
|RECORD=41|OwnerIndex=163|IndexInSheet=6|OwnerPartId=-1|Location.X=1198|Location.Y=850|Color=8388608|FontID=1|IsHidden=T|Text=-40°C|Name=Temperature Range Low
|RECORD=41|OwnerIndex=163|IndexInSheet=7|OwnerPartId=-1|Location.X=1198|Location.Y=850|Color=8388608|FontID=1|IsHidden=T|Text=1mm|Name=Height
|RECORD=41|OwnerIndex=163|IndexInSheet=8|OwnerPartId=-1|Location.X=1198|Location.Y=850|Color=8388608|FontID=2|IsHidden=T|Text=http://ww1.microchip.com/downloads/en/DeviceDoc/Atmel-8807-SEEPROM-AT24MAC402-602-Datasheet.pdf|Name=ComponentLink2URL
|RECORD=41|OwnerIndex=163|IndexInSheet=9|OwnerPartId=-1|Location.X=1198|Location.Y=850|Color=8388608|FontID=1|IsHidden=T|Text=SOT95P280X100-5|Name=Ipc Land Pattern Name
|RECORD=41|OwnerIndex=163|IndexInSheet=10|OwnerPartId=-1|Location.X=1198|Location.Y=850|Color=8388608|FontID=1|IsHidden=T|Text=2Kbits|Name=Memory Size
|RECORD=41|OwnerIndex=163|IndexInSheet=11|OwnerPartId=-1|Location.X=1198|Location.Y=850|Color=8388608|FontID=1|IsHidden=T|Text=IC|Name=Category
|RECORD=41|OwnerIndex=163|IndexInSheet=12|OwnerPartId=-1|Location.X=1198|Location.Y=850|Color=8388608|FontID=1|IsHidden=T|Text=EEPROM|Name=Memory Type
|RECORD=41|OwnerIndex=163|IndexInSheet=13|OwnerPartId=-1|Location.X=1198|Location.Y=850|Color=8388608|FontID=1|IsHidden=T|Text=IC EEPROM 2K I2C 1MHZ SOT23-5|Name=Digikey Description
|RECORD=41|OwnerIndex=163|IndexInSheet=14|OwnerPartId=-1|Location.X=1198|Location.Y=850|Color=8388608|FontID=1|IsHidden=T|Text=1.7V|Name=Min Supply Voltage
|RECORD=41|OwnerIndex=163|IndexInSheet=15|OwnerPartId=-1|Location.X=1198|Location.Y=850|Color=8388608|FontID=1|IsHidden=T|Text=AT24MAC402-STUM-T|Name=Manufacturer Part Number
|RECORD=41|OwnerIndex=163|IndexInSheet=16|OwnerPartId=-1|Location.X=1198|Location.Y=850|Color=8388608|FontID=1|IsHidden=T|Text=Integrated Circuits (ICs)|Name=Device Class L1
|RECORD=41|OwnerIndex=163|IndexInSheet=17|OwnerPartId=-1|Location.X=1198|Location.Y=850|Color=8388608|FontID=1|IsHidden=T|Text=+85°C|Name=Temperature Range High
|RECORD=41|OwnerIndex=163|IndexInSheet=18|OwnerPartId=-1|Location.X=1198|Location.Y=850|Color=8388608|FontID=1|IsHidden=T|Text=Datasheet|Name=ComponentLink2Description
|RECORD=41|OwnerIndex=163|IndexInSheet=19|OwnerPartId=-1|Location.X=1198|Location.Y=850|Color=8388608|FontID=1|IsHidden=T|Text=5.5V|Name=Max Supply Voltage
|RECORD=41|OwnerIndex=163|IndexInSheet=20|OwnerPartId=-1|Location.X=1198|Location.Y=850|Color=8388608|FontID=1|IsHidden=T|Text=TRUE|Name=RoHS
|RECORD=41|OwnerIndex=163|IndexInSheet=21|OwnerPartId=-1|Location.X=1198|Location.Y=850|Color=8388608|FontID=1|IsHidden=T|Text=1000kHz|Name=Frequency
|RECORD=41|OwnerIndex=163|IndexInSheet=22|OwnerPartId=-1|Location.X=1198|Location.Y=850|Color=8388608|FontID=1|IsHidden=T|Text=EEPROM Serial-I2C 2K-bit 256 x 8 1.8V/2.5V/3.3V/5V 5-Pin SOT-23 T/R|Name=Mouser Description
|RECORD=41|OwnerIndex=163|IndexInSheet=23|OwnerPartId=-1|Location.X=1198|Location.Y=850|Color=8388608|FontID=1|IsHidden=T|Text=Microchip|Name=Manufacturer
|RECORD=41|OwnerIndex=163|IndexInSheet=24|OwnerPartId=-1|Location.X=1198|Location.Y=850|Color=8388608|FontID=1|IsHidden=T|Text=0mm|Name=Standoff Height
|RECORD=41|OwnerIndex=163|IndexInSheet=25|OwnerPartId=-1|Location.X=1198|Location.Y=850|Color=8388608|FontID=2|IsHidden=T|Text=https://octopart.com/at24mac402-stum-t-microchip-77758112|Name=Octopart
|RECORD=41|OwnerIndex=163|IndexInSheet=26|OwnerPartId=-1|Location.X=1198|Location.Y=850|Color=8388608|FontID=1|IsHidden=T|Text=0.4-2mA|Name=Nominal Supply Current
|RECORD=41|OwnerIndex=163|IndexInSheet=27|OwnerPartId=-1|Location.X=1198|Location.Y=850|Color=8388608|FontID=1|IsHidden=T|Text=-40°C to +85°C|Name=Temperature
|RECORD=41|OwnerIndex=163|IndexInSheet=28|OwnerPartId=-1|Location.X=1198|Location.Y=850|Color=8388608|FontID=1|IsHidden=T|Text=5TS1|Name=Package
|RECORD=41|OwnerIndex=163|IndexInSheet=29|OwnerPartId=-1|Location.X=1198|Location.Y=850|Color=8388608|FontID=1|IsHidden=T|Text=EEPROM|Name=Device Class L3
|RECORD=41|OwnerIndex=163|IndexInSheet=30|OwnerPartId=-1|Location.X=1198|Location.Y=850|Color=8388608|FontID=1|IsHidden=T|Text=No|Name=Automotive
|RECORD=41|OwnerIndex=163|IndexInSheet=31|OwnerPartId=-1|Location.X=1198|Location.Y=850|Color=8388608|FontID=1|IsHidden=T|Text=0.55us|Name=Access Time
|RECORD=41|OwnerIndex=163|IndexInSheet=32|OwnerPartId=-1|Location.X=1198|Location.Y=850|Color=8388608|FontID=1|IsHidden=T|Text=Memory|Name=Device Class L2
|RECORD=41|OwnerIndex=163|IndexInSheet=33|OwnerPartId=-1|Location.X=1198|Location.Y=850|Color=8388608|FontID=1|IsHidden=T|Text=Yes|Name=Lead Free
|RECORD=41|OwnerIndex=163|IndexInSheet=34|OwnerPartId=-1|Location.X=1198|Location.Y=850|Color=8388608|FontID=1|IsHidden=T|Text=I2C,2-Wire|Name=Interface
|RECORD=34|OwnerIndex=163|IndexInSheet=-1|OwnerPartId=-1|Location.X=1220|Location.Y=850|Color=8388608|FontID=1|Text=U7|Name=Designator|ReadOnlyState=1
|RECORD=41|OwnerIndex=163|IndexInSheet=-1|OwnerPartId=1|Location.X=1220|Location.Y=780|Color=8388608|FontID=1|Text=AT24MAC402-STUM-T|Name=Comment
|RECORD=44|OwnerIndex=163
|RECORD=45|OwnerIndex=206|IndexInSheet=-1|UseComponentLibrary=T|ModelName=FP-5TS1-IPC_C|ModelType=PCBLIB|DatafileCount=1|ModelDatafileEntity0=FP-5TS1-IPC_C|ModelDatafileKind0=PCBLib|IsCurrent=T|DatalinksLocked=T|DatabaseDatalinksLocked=T
|RECORD=46|OwnerIndex=207
|RECORD=48|OwnerIndex=207
|RECORD=45|OwnerIndex=206|IndexInSheet=-1|UseComponentLibrary=T|ModelName=FP-5TS1-IPC_B|ModelType=PCBLIB|DatafileCount=1|ModelDatafileEntity0=FP-5TS1-IPC_B|ModelDatafileKind0=PCBLib|DatalinksLocked=T|DatabaseDatalinksLocked=T
|RECORD=46|OwnerIndex=210
|RECORD=48|OwnerIndex=210
|RECORD=45|OwnerIndex=206|IndexInSheet=-1|UseComponentLibrary=T|ModelName=FP-5TS1-IPC_A|ModelType=PCBLIB|DatafileCount=1|ModelDatafileEntity0=FP-5TS1-IPC_A|ModelDatafileKind0=PCBLib|DatalinksLocked=T|DatabaseDatalinksLocked=T
|RECORD=46|OwnerIndex=213
|RECORD=48|OwnerIndex=213
|RECORD=17|IndexInSheet=45|OwnerPartId=-1|ShowNetName=T|Location.X=1390|Location.Y=830|Color=255|FontID=1|Text=SDA|IsCrossSheetConnector=T
|RECORD=17|IndexInSheet=46|OwnerPartId=-1|ShowNetName=T|Location.X=1390|Location.Y=840|Color=255|FontID=1|Text=SCL|IsCrossSheetConnector=T
|RECORD=17|IndexInSheet=47|OwnerPartId=-1|ShowNetName=T|Location.X=1160|Location.Y=890|Orientation=1|Color=128|FontID=1|Text=+3.3V
|RECORD=17|IndexInSheet=48|OwnerPartId=-1|Style=4|ShowNetName=T|Location.X=1350|Location.Y=740|Orientation=3|Color=128|FontID=1|Text=GND
|RECORD=1|LibReference=CAP|ComponentDescription=C0603X104K5RACAUTO|PartCount=2|DisplayModeCount=2|IndexInSheet=49|OwnerPartId=-1|Location.X=260|Location.Y=780|Orientation=1|CurrentPartId=1|SourceLibraryName=Altium Content Vault|TargetFileName=*|AreaColor=11599871|Color=128|PartIDLocked=F|DesignItemId=CMP-2006-00003-1|AllPinCount=2
|RECORD=2|OwnerIndex=220|OwnerPartId=1|OwnerPartDisplayMode=1|FormalType=1|Electrical=4|PinConglomerate=35|PinLength=10|Location.X=270|Location.Y=780|Name=1|Designator=1|PinPropagationDelay=0.000000E+000
|RECORD=2|OwnerIndex=220|OwnerPartId=1|OwnerPartDisplayMode=1|FormalType=1|Electrical=4|PinConglomerate=33|PinLength=10|Location.X=270|Location.Y=790|Name=2|Designator=2|PinPropagationDelay=0.000000E+000
|RECORD=13|OwnerIndex=220|IsNotAccesible=T|IndexInSheet=2|OwnerPartId=1|OwnerPartDisplayMode=1|Location.X=278|Location.Y=780|Corner.X=262|Corner.Y=780|LineWidth=1|Color=16711680
|RECORD=13|OwnerIndex=220|IsNotAccesible=T|IndexInSheet=3|OwnerPartId=1|OwnerPartDisplayMode=1|Location.X=270|Location.Y=784|Corner.X=270|Corner.Y=790|LineWidth=1|Color=16711680
|RECORD=12|OwnerIndex=220|IsNotAccesible=T|IndexInSheet=4|OwnerPartId=1|OwnerPartDisplayMode=1|Location.X=270|Location.Y=800|Radius=16|LineWidth=1|StartAngle=241.000|EndAngle=270.000|Color=16711680
|RECORD=12|OwnerIndex=220|IsNotAccesible=T|IndexInSheet=5|OwnerPartId=1|OwnerPartDisplayMode=1|Location.X=270|Location.Y=800|Radius=16|LineWidth=1|StartAngle=270.000|EndAngle=299.000|Color=16711680
|RECORD=2|OwnerIndex=220|OwnerPartId=1|FormalType=1|Electrical=4|PinConglomerate=35|PinLength=10|Location.X=270|Location.Y=780|Name=1|Designator=1|PinPropagationDelay=0.000000E+000
|RECORD=2|OwnerIndex=220|OwnerPartId=1|FormalType=1|Electrical=4|PinConglomerate=33|PinLength=10|Location.X=270|Location.Y=790|Name=2|Designator=2|PinPropagationDelay=0.000000E+000
|RECORD=13|OwnerIndex=220|IsNotAccesible=T|IndexInSheet=8|OwnerPartId=1|Location.X=262|Location.Y=787|Corner.X=278|Corner.Y=787|LineWidth=1|Color=16711680
|RECORD=13|OwnerIndex=220|IsNotAccesible=T|IndexInSheet=9|OwnerPartId=1|Location.X=278|Location.Y=783|Corner.X=262|Corner.Y=783|LineWidth=1|Color=16711680
|RECORD=6|OwnerIndex=220|IsNotAccesible=T|IndexInSheet=10|OwnerPartId=1|LineWidth=1|Color=16711680|LocationCount=2|X1=270|Y1=780|X2=270|Y2=783
|RECORD=6|OwnerIndex=220|IsNotAccesible=T|IndexInSheet=11|OwnerPartId=1|LineWidth=1|Color=16711680|LocationCount=2|X1=270|Y1=790|X2=270|Y2=787
|RECORD=41|OwnerIndex=220|IndexInSheet=12|OwnerPartId=-1|Location.X=261|Location.Y=802|Color=8388608|FontID=1|IsHidden=T|Text=Kemet|Name=Manufacturer
|RECORD=41|OwnerIndex=220|IndexInSheet=13|OwnerPartId=-1|Location.X=261|Location.Y=802|Color=8388608|FontID=1|IsHidden=T|Text=C0603X104K5RACAUTO|Name=Part Number
|RECORD=34|OwnerIndex=220|IndexInSheet=-1|OwnerPartId=-1|Location.X=279|Location.Y=781|Color=8388608|FontID=4|Text=C59|Name=Designator|ReadOnlyState=1
|RECORD=41|OwnerIndex=220|IndexInSheet=-1|OwnerPartId=-1|Location.X=279|Location.Y=771|Color=8388608|FontID=4|Text=0.1uF|Name=Comment
|RECORD=44|OwnerIndex=220
|RECORD=45|OwnerIndex=241|IndexInSheet=-1|Description=Chip Capacitor, 2-Leads, Body 1.60x0.80mm, IPC Low Density|UseComponentLibrary=T|ModelName=CAPC1608X87X45ML20T05|ModelType=PCBLIB|DatafileCount=1|ModelDatafileEntity0=CAPC1608X87X45ML20T05|ModelDatafileKind0=PCBLib|IsCurrent=T|DatalinksLocked=T|DatabaseDatalinksLocked=T
|RECORD=46|OwnerIndex=242
|RECORD=48|OwnerIndex=242
|RECORD=41|OwnerIndex=244|IndexInSheet=-1|OwnerPartId=-1|Color=8388608|FontID=1|Text=2D|Name=Available Preview Images
|RECORD=45|OwnerIndex=241|IndexInSheet=-1|Description=Chip Capacitor, 2-Leads, Body 1.60x0.80mm, IPC High Density|UseComponentLibrary=T|ModelName=CAPC1608X87X45LL20T05|ModelType=PCBLIB|DatafileCount=1|ModelDatafileEntity0=CAPC1608X87X45LL20T05|ModelDatafileKind0=PCBLib|DatalinksLocked=T|DatabaseDatalinksLocked=T
|RECORD=46|OwnerIndex=246
|RECORD=48|OwnerIndex=246
|RECORD=41|OwnerIndex=248|IndexInSheet=-1|OwnerPartId=-1|Color=8388608|FontID=1|Text=2D|Name=Available Preview Images
|RECORD=45|OwnerIndex=241|IndexInSheet=-1|Description=Chip Capacitor, 2-Leads, Body 1.60x0.80mm, IPC Medium Density|UseComponentLibrary=T|ModelName=CAPC1608X87X45NL20T05|ModelType=PCBLIB|DatafileCount=1|ModelDatafileEntity0=CAPC1608X87X45NL20T05|ModelDatafileKind0=PCBLib|DatalinksLocked=T|DatabaseDatalinksLocked=T
|RECORD=46|OwnerIndex=250
|RECORD=48|OwnerIndex=250
|RECORD=41|OwnerIndex=252|IndexInSheet=-1|OwnerPartId=-1|Color=8388608|FontID=1|Text=2D|Name=Available Preview Images
|RECORD=1|LibReference=CAP|ComponentDescription=C0603X104K5RACAUTO|PartCount=2|DisplayModeCount=2|IndexInSheet=50|OwnerPartId=-1|Location.X=360|Location.Y=780|Orientation=1|CurrentPartId=1|SourceLibraryName=Altium Content Vault|TargetFileName=*|AreaColor=11599871|Color=128|PartIDLocked=F|DesignItemId=CMP-2006-00003-1|AllPinCount=2
|RECORD=2|OwnerIndex=254|OwnerPartId=1|OwnerPartDisplayMode=1|FormalType=1|Electrical=4|PinConglomerate=35|PinLength=10|Location.X=370|Location.Y=780|Name=1|Designator=1|PinPropagationDelay=0.000000E+000
|RECORD=2|OwnerIndex=254|OwnerPartId=1|OwnerPartDisplayMode=1|FormalType=1|Electrical=4|PinConglomerate=33|PinLength=10|Location.X=370|Location.Y=790|Name=2|Designator=2|PinPropagationDelay=0.000000E+000
|RECORD=13|OwnerIndex=254|IsNotAccesible=T|IndexInSheet=2|OwnerPartId=1|OwnerPartDisplayMode=1|Location.X=378|Location.Y=780|Corner.X=362|Corner.Y=780|LineWidth=1|Color=16711680
|RECORD=13|OwnerIndex=254|IsNotAccesible=T|IndexInSheet=3|OwnerPartId=1|OwnerPartDisplayMode=1|Location.X=370|Location.Y=784|Corner.X=370|Corner.Y=790|LineWidth=1|Color=16711680
|RECORD=12|OwnerIndex=254|IsNotAccesible=T|IndexInSheet=4|OwnerPartId=1|OwnerPartDisplayMode=1|Location.X=370|Location.Y=800|Radius=16|LineWidth=1|StartAngle=241.000|EndAngle=270.000|Color=16711680
|RECORD=12|OwnerIndex=254|IsNotAccesible=T|IndexInSheet=5|OwnerPartId=1|OwnerPartDisplayMode=1|Location.X=370|Location.Y=800|Radius=16|LineWidth=1|StartAngle=270.000|EndAngle=299.000|Color=16711680
|RECORD=2|OwnerIndex=254|OwnerPartId=1|FormalType=1|Electrical=4|PinConglomerate=35|PinLength=10|Location.X=370|Location.Y=780|Name=1|Designator=1|PinPropagationDelay=0.000000E+000
|RECORD=2|OwnerIndex=254|OwnerPartId=1|FormalType=1|Electrical=4|PinConglomerate=33|PinLength=10|Location.X=370|Location.Y=790|Name=2|Designator=2|PinPropagationDelay=0.000000E+000
|RECORD=13|OwnerIndex=254|IsNotAccesible=T|IndexInSheet=8|OwnerPartId=1|Location.X=362|Location.Y=787|Corner.X=378|Corner.Y=787|LineWidth=1|Color=16711680
|RECORD=13|OwnerIndex=254|IsNotAccesible=T|IndexInSheet=9|OwnerPartId=1|Location.X=378|Location.Y=783|Corner.X=362|Corner.Y=783|LineWidth=1|Color=16711680
|RECORD=6|OwnerIndex=254|IsNotAccesible=T|IndexInSheet=10|OwnerPartId=1|LineWidth=1|Color=16711680|LocationCount=2|X1=370|Y1=780|X2=370|Y2=783
|RECORD=6|OwnerIndex=254|IsNotAccesible=T|IndexInSheet=11|OwnerPartId=1|LineWidth=1|Color=16711680|LocationCount=2|X1=370|Y1=790|X2=370|Y2=787
|RECORD=41|OwnerIndex=254|IndexInSheet=12|OwnerPartId=-1|Location.X=361|Location.Y=802|Color=8388608|FontID=1|IsHidden=T|Text=Kemet|Name=Manufacturer
|RECORD=41|OwnerIndex=254|IndexInSheet=13|OwnerPartId=-1|Location.X=361|Location.Y=802|Color=8388608|FontID=1|IsHidden=T|Text=C0603X104K5RACAUTO|Name=Part Number
|RECORD=34|OwnerIndex=254|IndexInSheet=-1|OwnerPartId=-1|Location.X=379|Location.Y=781|Color=8388608|FontID=4|Text=C61|Name=Designator|ReadOnlyState=1
|RECORD=41|OwnerIndex=254|IndexInSheet=-1|OwnerPartId=-1|Location.X=379|Location.Y=771|Color=8388608|FontID=4|Text=0.1uF|Name=Comment
|RECORD=44|OwnerIndex=254
|RECORD=45|OwnerIndex=275|IndexInSheet=-1|Description=Chip Capacitor, 2-Leads, Body 1.60x0.80mm, IPC Low Density|UseComponentLibrary=T|ModelName=CAPC1608X87X45ML20T05|ModelType=PCBLIB|DatafileCount=1|ModelDatafileEntity0=CAPC1608X87X45ML20T05|ModelDatafileKind0=PCBLib|IsCurrent=T|DatalinksLocked=T|DatabaseDatalinksLocked=T
|RECORD=46|OwnerIndex=276
|RECORD=48|OwnerIndex=276
|RECORD=41|OwnerIndex=278|IndexInSheet=-1|OwnerPartId=-1|Color=8388608|FontID=1|Text=2D|Name=Available Preview Images
|RECORD=45|OwnerIndex=275|IndexInSheet=-1|Description=Chip Capacitor, 2-Leads, Body 1.60x0.80mm, IPC High Density|UseComponentLibrary=T|ModelName=CAPC1608X87X45LL20T05|ModelType=PCBLIB|DatafileCount=1|ModelDatafileEntity0=CAPC1608X87X45LL20T05|ModelDatafileKind0=PCBLib|DatalinksLocked=T|DatabaseDatalinksLocked=T
|RECORD=46|OwnerIndex=280
|RECORD=48|OwnerIndex=280
|RECORD=41|OwnerIndex=282|IndexInSheet=-1|OwnerPartId=-1|Color=8388608|FontID=1|Text=2D|Name=Available Preview Images
|RECORD=45|OwnerIndex=275|IndexInSheet=-1|Description=Chip Capacitor, 2-Leads, Body 1.60x0.80mm, IPC Medium Density|UseComponentLibrary=T|ModelName=CAPC1608X87X45NL20T05|ModelType=PCBLIB|DatafileCount=1|ModelDatafileEntity0=CAPC1608X87X45NL20T05|ModelDatafileKind0=PCBLib|DatalinksLocked=T|DatabaseDatalinksLocked=T
|RECORD=46|OwnerIndex=284
|RECORD=48|OwnerIndex=284
|RECORD=41|OwnerIndex=286|IndexInSheet=-1|OwnerPartId=-1|Color=8388608|FontID=1|Text=2D|Name=Available Preview Images
|RECORD=1|LibReference=CAP|ComponentDescription=C0603X104K5RACAUTO|PartCount=2|DisplayModeCount=2|IndexInSheet=51|OwnerPartId=-1|Location.X=1150|Location.Y=760|Orientation=1|CurrentPartId=1|SourceLibraryName=Altium Content Vault|TargetFileName=*|AreaColor=11599871|Color=128|PartIDLocked=F|DesignItemId=CMP-2006-00003-1|AllPinCount=2
|RECORD=2|OwnerIndex=288|OwnerPartId=1|OwnerPartDisplayMode=1|FormalType=1|Electrical=4|PinConglomerate=35|PinLength=10|Location.X=1160|Location.Y=760|Name=1|Designator=1|PinPropagationDelay=0.000000E+000
|RECORD=2|OwnerIndex=288|OwnerPartId=1|OwnerPartDisplayMode=1|FormalType=1|Electrical=4|PinConglomerate=33|PinLength=10|Location.X=1160|Location.Y=770|Name=2|Designator=2|PinPropagationDelay=0.000000E+000
|RECORD=13|OwnerIndex=288|IsNotAccesible=T|IndexInSheet=2|OwnerPartId=1|OwnerPartDisplayMode=1|Location.X=1168|Location.Y=760|Corner.X=1152|Corner.Y=760|LineWidth=1|Color=16711680
|RECORD=13|OwnerIndex=288|IsNotAccesible=T|IndexInSheet=3|OwnerPartId=1|OwnerPartDisplayMode=1|Location.X=1160|Location.Y=764|Corner.X=1160|Corner.Y=770|LineWidth=1|Color=16711680
|RECORD=12|OwnerIndex=288|IsNotAccesible=T|IndexInSheet=4|OwnerPartId=1|OwnerPartDisplayMode=1|Location.X=1160|Location.Y=780|Radius=16|LineWidth=1|StartAngle=241.000|EndAngle=270.000|Color=16711680
|RECORD=12|OwnerIndex=288|IsNotAccesible=T|IndexInSheet=5|OwnerPartId=1|OwnerPartDisplayMode=1|Location.X=1160|Location.Y=780|Radius=16|LineWidth=1|StartAngle=270.000|EndAngle=299.000|Color=16711680
|RECORD=2|OwnerIndex=288|OwnerPartId=1|FormalType=1|Electrical=4|PinConglomerate=35|PinLength=10|Location.X=1160|Location.Y=760|Name=1|Designator=1|PinPropagationDelay=0.000000E+000
|RECORD=2|OwnerIndex=288|OwnerPartId=1|FormalType=1|Electrical=4|PinConglomerate=33|PinLength=10|Location.X=1160|Location.Y=770|Name=2|Designator=2|PinPropagationDelay=0.000000E+000
|RECORD=13|OwnerIndex=288|IsNotAccesible=T|IndexInSheet=8|OwnerPartId=1|Location.X=1152|Location.Y=767|Corner.X=1168|Corner.Y=767|LineWidth=1|Color=16711680
|RECORD=13|OwnerIndex=288|IsNotAccesible=T|IndexInSheet=9|OwnerPartId=1|Location.X=1168|Location.Y=763|Corner.X=1152|Corner.Y=763|LineWidth=1|Color=16711680
|RECORD=6|OwnerIndex=288|IsNotAccesible=T|IndexInSheet=10|OwnerPartId=1|LineWidth=1|Color=16711680|LocationCount=2|X1=1160|Y1=760|X2=1160|Y2=763
|RECORD=6|OwnerIndex=288|IsNotAccesible=T|IndexInSheet=11|OwnerPartId=1|LineWidth=1|Color=16711680|LocationCount=2|X1=1160|Y1=770|X2=1160|Y2=767
|RECORD=41|OwnerIndex=288|IndexInSheet=12|OwnerPartId=-1|Location.X=1151|Location.Y=782|Color=8388608|FontID=1|IsHidden=T|Text=Kemet|Name=Manufacturer
|RECORD=41|OwnerIndex=288|IndexInSheet=13|OwnerPartId=-1|Location.X=1151|Location.Y=782|Color=8388608|FontID=1|IsHidden=T|Text=C0603X104K5RACAUTO|Name=Part Number
|RECORD=34|OwnerIndex=288|IndexInSheet=-1|OwnerPartId=-1|Location.X=1169|Location.Y=761|Color=8388608|FontID=4|Text=C25|Name=Designator|ReadOnlyState=1
|RECORD=41|OwnerIndex=288|IndexInSheet=-1|OwnerPartId=-1|Location.X=1169|Location.Y=751|Color=8388608|FontID=4|Text=0.1uF|Name=Comment
|RECORD=44|OwnerIndex=288
|RECORD=45|OwnerIndex=309|IndexInSheet=-1|Description=Chip Capacitor, 2-Leads, Body 1.60x0.80mm, IPC Low Density|UseComponentLibrary=T|ModelName=CAPC1608X87X45ML20T05|ModelType=PCBLIB|DatafileCount=1|ModelDatafileEntity0=CAPC1608X87X45ML20T05|ModelDatafileKind0=PCBLib|IsCurrent=T|DatalinksLocked=T|DatabaseDatalinksLocked=T
|RECORD=46|OwnerIndex=310
|RECORD=48|OwnerIndex=310
|RECORD=41|OwnerIndex=312|IndexInSheet=-1|OwnerPartId=-1|Color=8388608|FontID=1|Text=2D|Name=Available Preview Images
|RECORD=45|OwnerIndex=309|IndexInSheet=-1|Description=Chip Capacitor, 2-Leads, Body 1.60x0.80mm, IPC High Density|UseComponentLibrary=T|ModelName=CAPC1608X87X45LL20T05|ModelType=PCBLIB|DatafileCount=1|ModelDatafileEntity0=CAPC1608X87X45LL20T05|ModelDatafileKind0=PCBLib|DatalinksLocked=T|DatabaseDatalinksLocked=T
|RECORD=46|OwnerIndex=314
|RECORD=48|OwnerIndex=314
|RECORD=41|OwnerIndex=316|IndexInSheet=-1|OwnerPartId=-1|Color=8388608|FontID=1|Text=2D|Name=Available Preview Images
|RECORD=45|OwnerIndex=309|IndexInSheet=-1|Description=Chip Capacitor, 2-Leads, Body 1.60x0.80mm, IPC Medium Density|UseComponentLibrary=T|ModelName=CAPC1608X87X45NL20T05|ModelType=PCBLIB|DatafileCount=1|ModelDatafileEntity0=CAPC1608X87X45NL20T05|ModelDatafileKind0=PCBLib|DatalinksLocked=T|DatabaseDatalinksLocked=T
|RECORD=46|OwnerIndex=318
|RECORD=48|OwnerIndex=318
|RECORD=41|OwnerIndex=320|IndexInSheet=-1|OwnerPartId=-1|Color=8388608|FontID=1|Text=2D|Name=Available Preview Images
|RECORD=17|IndexInSheet=52|OwnerPartId=-1|ShowNetName=T|Location.X=1110|Location.Y=890|Orientation=1|Color=128|FontID=1|Text=+3.3V
|RECORD=17|IndexInSheet=53|OwnerPartId=-1|Style=4|ShowNetName=T|Location.X=1160|Location.Y=740|Orientation=3|Color=128|FontID=1|Text=GND
|RECORD=17|IndexInSheet=54|OwnerPartId=-1|ShowNetName=T|Location.X=1090|Location.Y=800|Orientation=2|Color=255|FontID=1|Text=EXT_EEPROM_WP|IsCrossSheetConnector=T
|RECORD=1|LibReference=RES-2|ComponentDescription=Chip Resistor, 10 KOhm, +/- 1%, 0.1 W, -55 to 155 degC, 0603 (1608 Metric), RoHS, Tape and Reel RMCF0603FT10K0|PartCount=2|DisplayModeCount=1|IndexInSheet=55|OwnerPartId=-1|Location.X=1110|Location.Y=840|Orientation=1|CurrentPartId=1|LibraryPath=*|SourceLibraryName=Altium Content Vault|TargetFileName=*|AreaColor=11599871|Color=128|PartIDLocked=T|DesignItemId=CMP-2000-06990-1|AllPinCount=2
|RECORD=2|OwnerIndex=325|OwnerPartId=1|FormalType=1|Electrical=4|PinConglomerate=33|PinLength=10|Location.X=1110|Location.Y=860|Name=2|Designator=2|PinPropagationDelay=0.000000E+000
|RECORD=2|OwnerIndex=325|OwnerPartId=1|FormalType=1|Electrical=4|PinConglomerate=35|PinLength=10|Location.X=1110|Location.Y=840|Name=1|Designator=1|PinPropagationDelay=0.000000E+000
|RECORD=6|OwnerIndex=325|IsNotAccesible=T|IndexInSheet=2|OwnerPartId=1|LineWidth=1|Color=16711680|LocationCount=10|X1=1110|Y1=860|X2=1110|Y2=856|X3=1112|Y3=855|X4=1108|Y4=853|X5=1112|Y5=851|X6=1108|Y6=849|X7=1112|Y7=847|X8=1108|Y8=845|X9=1110|Y9=844|X10=1110|Y10=840
|RECORD=41|OwnerIndex=325|IndexInSheet=3|OwnerPartId=-1|Location.X=1107|Location.Y=872|Color=8388608|FontID=1|IsHidden=T|Text=0603(1608Metric)|Name=Package / Case
|RECORD=41|OwnerIndex=325|IndexInSheet=4|OwnerPartId=-1|Location.X=1107|Location.Y=872|Color=8388608|FontID=1|IsHidden=T|Text=01/2017|Name=Datasheet Version
|RECORD=41|OwnerIndex=325|IndexInSheet=5|OwnerPartId=-1|Location.X=1107|Location.Y=872|Color=8388608|FontID=1|IsHidden=T|Text=10k|Name=Resistance (Ohms)
|RECORD=41|OwnerIndex=325|IndexInSheet=6|OwnerPartId=-1|Location.X=1107|Location.Y=872|Color=8388608|FontID=1|IsHidden=T|Text=AutomotiveAEC-Q200|Name=Features
|RECORD=41|OwnerIndex=325|IndexInSheet=7|OwnerPartId=-1|Location.X=1107|Location.Y=872|Color=8388608|FontID=1|IsHidden=T|Text=CutTape(CT)|Name=Packaging
|RECORD=41|OwnerIndex=325|IndexInSheet=8|OwnerPartId=-1|Location.X=1107|Location.Y=872|Color=8388608|FontID=1|IsHidden=T|Text=RMCF|Name=Series
|RECORD=41|OwnerIndex=325|IndexInSheet=9|OwnerPartId=-1|Location.X=1107|Location.Y=872|Color=8388608|FontID=1|IsHidden=T|Text=0.022"(0.55mm)|Name=Height
|RECORD=41|OwnerIndex=325|IndexInSheet=10|OwnerPartId=-1|Location.X=1107|Location.Y=872|Color=8388608|FontID=1|IsHidden=T|Text=±1%|Name=Tolerance
|RECORD=41|OwnerIndex=325|IndexInSheet=11|OwnerPartId=-1|Location.X=1107|Location.Y=872|Color=8388608|FontID=2|IsHidden=T|Text=https://www.seielect.com/|Name=Manufacturer URL
|RECORD=41|OwnerIndex=325|IndexInSheet=12|OwnerPartId=-1|Location.X=1107|Location.Y=872|Color=8388608|FontID=2|IsHidden=T|Text=https://www.seielect.com/Catalog/SEI-RMCF_RMCP.pdf|Name=Datasheet URL
|RECORD=41|OwnerIndex=325|IndexInSheet=13|OwnerPartId=-1|Location.X=1107|Location.Y=872|Color=8388608|FontID=1|IsHidden=T|Text=0603|Name=Supplier Device Package
|RECORD=41|OwnerIndex=325|IndexInSheet=14|OwnerPartId=-1|Location.X=1107|Location.Y=872|Color=8388608|FontID=1|IsHidden=T|Text=2|Name=Number of Terminations
|RECORD=41|OwnerIndex=325|IndexInSheet=15|OwnerPartId=-1|Location.X=1107|Location.Y=872|Color=8388608|FontID=1|IsHidden=T|Text=ChipResistor-SurfaceMount|Name=Family
|RECORD=41|OwnerIndex=325|IndexInSheet=16|OwnerPartId=-1|Location.X=1107|Location.Y=872|Color=8388608|FontID=1|IsHidden=T|Text=0603|Name=Package Reference
|RECORD=41|OwnerIndex=325|IndexInSheet=17|OwnerPartId=-1|Location.X=1107|Location.Y=872|Color=8388608|FontID=1|IsHidden=T|Text=0.061"Lx0.031"W(1.55mmx0.80mm)|Name=Size / Dimension
|RECORD=41|OwnerIndex=325|IndexInSheet=18|OwnerPartId=-1|Location.X=1107|Location.Y=872|Color=8388608|FontID=1|IsHidden=T|Text=SurfaceMount|Name=Mounting Technology
|RECORD=41|OwnerIndex=325|IndexInSheet=19|OwnerPartId=-1|Location.X=1107|Location.Y=872|Color=8388608|FontID=1|IsHidden=T|Text=2-Pin Surface Mount Device, Body 1.55 x 0.8 mm|Name=Package Description
|RECORD=41|OwnerIndex=325|IndexInSheet=20|OwnerPartId=-1|Location.X=1107|Location.Y=872|Color=8388608|FontID=1|IsHidden=T|Text=-55°C~155°C|Name=Operating Temperature
|RECORD=41|OwnerIndex=325|IndexInSheet=21|OwnerPartId=-1|Location.X=1107|Location.Y=872|Color=8388608|FontID=1|IsHidden=T|Text=±100ppm/°C|Name=Temperature Coefficient
|RECORD=41|OwnerIndex=325|IndexInSheet=22|OwnerPartId=-1|Location.X=1107|Location.Y=872|Color=8388608|FontID=1|IsHidden=T|Text=ThickFilm|Name=Composition
|RECORD=41|OwnerIndex=325|IndexInSheet=23|OwnerPartId=-1|Location.X=1107|Location.Y=872|Color=8388608|FontID=1|IsHidden=T|Text=0.1W,1/10W|Name=Power (Watts)
|RECORD=41|OwnerIndex=325|IndexInSheet=24|OwnerPartId=-1|Location.X=1107|Location.Y=872|Color=8388608|FontID=1|IsHidden=T|Text=Stackpole-Electronics-Inc.|Name=Manufacturer
|RECORD=41|OwnerIndex=325|IndexInSheet=25|OwnerPartId=-1|Location.X=1107|Location.Y=872|Color=8388608|FontID=1|IsHidden=T|Text=Resistors|Name=Category
|RECORD=34|OwnerIndex=325|IndexInSheet=-1|OwnerPartId=-1|Location.X=1113|Location.Y=851|Color=8388608|FontID=1|Text=R37|Name=Designator|ReadOnlyState=1
|RECORD=41|OwnerIndex=325|IndexInSheet=-1|OwnerPartId=-1|Location.X=1113|Location.Y=841|Color=8388608|FontID=1|Text=10K|Name=Comment
|RECORD=44|OwnerIndex=325
|RECORD=45|OwnerIndex=356|IndexInSheet=-1|Description=Chip Resistor, 2-Leads, Body 1.7x0.95mm, IPC High Density|UseComponentLibrary=T|ModelName=RESC1608X55X30LL15T20|ModelType=PCBLIB|DatafileCount=1|ModelDatafileEntity0=RESC1608X55X30LL15T20|ModelDatafileKind0=PCBLib|IsCurrent=T|DatalinksLocked=T|DatabaseDatalinksLocked=T
|RECORD=46|OwnerIndex=357
|RECORD=48|OwnerIndex=357
|RECORD=41|OwnerIndex=359|IndexInSheet=-1|OwnerPartId=-1|Color=8388608|FontID=1|Text=2D|Name=Available Preview Images
|RECORD=45|OwnerIndex=356|IndexInSheet=-1|Description=Chip Resistor, 2-Leads, Body 1.7x0.95mm, IPC Low Density|UseComponentLibrary=T|ModelName=RESC1608X55X30ML15T20|ModelType=PCBLIB|DatafileCount=1|ModelDatafileEntity0=RESC1608X55X30ML15T20|ModelDatafileKind0=PCBLib|DatalinksLocked=T|DatabaseDatalinksLocked=T
|RECORD=46|OwnerIndex=361
|RECORD=48|OwnerIndex=361
|RECORD=41|OwnerIndex=363|IndexInSheet=-1|OwnerPartId=-1|Color=8388608|FontID=1|Text=2D|Name=Available Preview Images
|RECORD=45|OwnerIndex=356|IndexInSheet=-1|Description=Chip Resistor, 2-Leads, Body 1.7x0.95mm, IPC Medium Density|UseComponentLibrary=T|ModelName=RESC1608X55X30NL15T20|ModelType=PCBLIB|DatafileCount=1|ModelDatafileEntity0=RESC1608X55X30NL15T20|ModelDatafileKind0=PCBLib|DatalinksLocked=T|DatabaseDatalinksLocked=T
|RECORD=46|OwnerIndex=365
|RECORD=48|OwnerIndex=365
|RECORD=41|OwnerIndex=367|IndexInSheet=-1|OwnerPartId=-1|Color=8388608|FontID=1|Text=2D|Name=Available Preview Images
|RECORD=41|IndexInSheet=56|OwnerPartId=-1|Color=8388608|FontID=1|IsHidden=T|Name=ConfigurationParameters|ReadOnlyState=1
|RECORD=41|IndexInSheet=57|OwnerPartId=-1|Color=8388608|FontID=1|IsHidden=T|Name=ConfiguratorName|ReadOnlyState=1
|RECORD=41|IndexInSheet=58|OwnerPartId=-1|Color=8388608|FontID=1|IsHidden=T|Name=VersionControl_RevNumber|ReadOnlyState=1
|RECORD=41|IndexInSheet=59|OwnerPartId=-1|Color=8388608|FontID=1|IsHidden=T|Name=IsUserConfigurable|ReadOnlyState=1
|RECORD=41|IndexInSheet=60|OwnerPartId=-1|Color=8388608|FontID=1|IsHidden=T|Name=VersionControl_ProjFolderRevNumber|ReadOnlyState=1
|RECORD=41|IndexInSheet=61|OwnerPartId=-1|Color=8388608|FontID=1|IsHidden=T|Name=SPICEModelCache|ReadOnlyState=1
|RECORD=4|IndexInSheet=62|OwnerPartId=-1|Location.X=1210|Location.Y=886|Color=8388608|FontID=5|Text=EEPROM
|RECORD=1|LibReference=d58e2f6669bc67e6a2bc6a28610ca79|ComponentDescription=SENSOR PRESSURE HUMIDITY TEMP|PartCount=2|DisplayModeCount=1|IndexInSheet=63|OwnerPartId=-1|Location.X=470|Location.Y=420|CurrentPartId=1|LibraryPath=*|SourceLibraryName=Altium Content Vault|TargetFileName=*|AreaColor=11599871|Color=128|PartIDLocked=T|DesignItemId=CMP-2000-05073-3|AllPinCount=8
|RECORD=14|OwnerIndex=376|IsNotAccesible=T|OwnerPartId=1|Location.X=490|Location.Y=350|Corner.X=590|Corner.Y=430|LineWidth=1|Color=128|AreaColor=11599871|IsSolid=T
|RECORD=2|OwnerIndex=376|OwnerPartId=1|Electrical=7|PinConglomerate=58|PinLength=20|Location.X=490|Location.Y=420|Name=VDD|Designator=8|PinPropagationDelay=0.000000E+000
|RECORD=2|OwnerIndex=376|OwnerPartId=1|Electrical=7|PinConglomerate=58|PinLength=20|Location.X=490|Location.Y=410|Name=VDDIO|Designator=6|PinPropagationDelay=0.000000E+000
|RECORD=2|OwnerIndex=376|OwnerPartId=1|PinConglomerate=56|PinLength=20|Location.X=590|Location.Y=390|Name=C\S\|Designator=2|PinPropagationDelay=0.000000E+000
|RECORD=2|OwnerIndex=376|OwnerPartId=1|SymBol_InnerEdge=3|PinConglomerate=56|PinLength=20|Location.X=590|Location.Y=420|Name=SCK|Designator=4|PinPropagationDelay=0.000000E+000
|RECORD=2|OwnerIndex=376|OwnerPartId=1|Electrical=1|PinConglomerate=56|PinLength=20|Location.X=590|Location.Y=410|Name=SDI|Designator=3|PinPropagationDelay=0.000000E+000
|RECORD=2|OwnerIndex=376|OwnerPartId=1|Electrical=1|PinConglomerate=56|PinLength=20|Location.X=590|Location.Y=400|Name=SDO|Designator=5|PinPropagationDelay=0.000000E+000
|RECORD=2|OwnerIndex=376|OwnerPartId=1|Electrical=7|PinConglomerate=56|PinLength=20|Location.X=590|Location.Y=370|Name=GND|Designator=1|PinPropagationDelay=0.000000E+000
|RECORD=2|OwnerIndex=376|OwnerPartId=1|Electrical=7|PinConglomerate=56|PinLength=20|Location.X=590|Location.Y=360|Name=GND|Designator=7|PinPropagationDelay=0.000000E+000
|RECORD=41|OwnerIndex=376|IndexInSheet=9|OwnerPartId=-1|Location.X=468|Location.Y=430|Color=8388608|FontID=1|IsHidden=T|Text=Temperature|Name=Sensor Type
|RECORD=41|OwnerIndex=376|IndexInSheet=10|OwnerPartId=-1|Location.X=468|Location.Y=430|Color=8388608|FontID=1|IsHidden=T|Text=-40°C|Name=Min Operating Temperature
|RECORD=41|OwnerIndex=376|IndexInSheet=11|OwnerPartId=-1|Location.X=468|Location.Y=430|Color=8388608|FontID=1|IsHidden=T|Text=3%|Name=Accuracy
|RECORD=41|OwnerIndex=376|IndexInSheet=12|OwnerPartId=-1|Location.X=468|Location.Y=430|Color=8388608|FontID=1|IsHidden=T|Text=85°C|Name=Max Operating Temperature
|RECORD=41|OwnerIndex=376|IndexInSheet=13|OwnerPartId=-1|Location.X=468|Location.Y=430|Color=8388608|FontID=1|IsHidden=T|Text=LGA|Name=Case/Package
|RECORD=41|OwnerIndex=376|IndexInSheet=14|OwnerPartId=-1|Location.X=468|Location.Y=430|Color=8388608|FontID=1|IsHidden=T|Text=Cut Tape|Name=Packaging
|RECORD=41|OwnerIndex=376|IndexInSheet=15|OwnerPartId=-1|Location.X=468|Location.Y=430|Color=8388608|FontID=1|IsHidden=T|Text=Surface Mount|Name=Mount
|RECORD=41|OwnerIndex=376|IndexInSheet=16|OwnerPartId=-1|Location.X=468|Location.Y=430|Color=8388608|FontID=1|IsHidden=T|Text=1s|Name=Response Time
|RECORD=41|OwnerIndex=376|IndexInSheet=17|OwnerPartId=-1|Location.X=468|Location.Y=430|Color=8388608|FontID=1|IsHidden=T|Text=SPI|Name=Output Type
|RECORD=41|OwnerIndex=376|IndexInSheet=18|OwnerPartId=-1|Location.X=468|Location.Y=430|Color=8388608|FontID=1|IsHidden=T|Text=Lead Free|Name=Lead Free
|RECORD=41|OwnerIndex=376|IndexInSheet=19|OwnerPartId=-1|Location.X=468|Location.Y=430|Color=8388608|FontID=1|IsHidden=T|Text=8|Name=Number of Pins
|RECORD=34|OwnerIndex=376|IndexInSheet=-1|OwnerPartId=-1|Location.X=490|Location.Y=430|Color=8388608|FontID=1|Text=U14|Name=Designator|ReadOnlyState=1
|RECORD=41|OwnerIndex=376|IndexInSheet=-1|OwnerPartId=1|Location.X=490|Location.Y=340|Color=8388608|FontID=1|Text=BME280|Name=Comment
|RECORD=44|OwnerIndex=376
|RECORD=45|OwnerIndex=407|IndexInSheet=-1|UseComponentLibrary=T|ModelName=FP-BME280-MFG|ModelType=PCBLIB|DatafileCount=1|ModelDatafileEntity0=FP-BME280-MFG|ModelDatafileKind0=PCBLib|IsCurrent=T|DatalinksLocked=T|DatabaseDatalinksLocked=T
|RECORD=46|OwnerIndex=408
|RECORD=48|OwnerIndex=408
|RECORD=1|LibReference=34da024cb04dfcb8cf696aa13940ccc|ComponentDescription=IMU ACCEL/GYRO/MAG|PartCount=2|DisplayModeCount=1|IndexInSheet=64|OwnerPartId=-1|Location.X=1130|Location.Y=430|CurrentPartId=1|LibraryPath=*|SourceLibraryName=Altium Content Vault|TargetFileName=*|AreaColor=11599871|Color=128|PartIDLocked=T|DesignItemId=CMP-191067-000010-1|AllPinCount=14
|RECORD=14|OwnerIndex=411|IsNotAccesible=T|OwnerPartId=1|Location.X=1150|Location.Y=330|Corner.X=1270|Corner.Y=440|LineWidth=1|Color=128|AreaColor=11599871|IsSolid=T
|RECORD=2|OwnerIndex=411|OwnerPartId=1|Electrical=7|PinConglomerate=58|PinLength=20|Location.X=1150|Location.Y=430|Name=VDD|Designator=8|PinName_PositionConglomerate=16|Name_CustomFontID=1|PinDesignator_PositionConglomerate=16|Designator_CustomFontID=1|PinPropagationDelay=0.000000E+000
|RECORD=2|OwnerIndex=411|OwnerPartId=1|Electrical=7|PinConglomerate=58|PinLength=20|Location.X=1150|Location.Y=420|Name=VDDIO|Designator=5|PinName_PositionConglomerate=16|Name_CustomFontID=1|PinDesignator_PositionConglomerate=16|Designator_CustomFontID=1|PinPropagationDelay=0.000000E+000
|RECORD=2|OwnerIndex=411|OwnerPartId=1|Electrical=1|PinConglomerate=56|PinLength=20|Location.X=1270|Location.Y=430|Name=INT1|Designator=4|PinName_PositionConglomerate=16|Name_CustomFontID=1|PinDesignator_PositionConglomerate=16|Designator_CustomFontID=1|PinPropagationDelay=0.000000E+000
|RECORD=2|OwnerIndex=411|OwnerPartId=1|Electrical=1|PinConglomerate=56|PinLength=20|Location.X=1270|Location.Y=420|Name=INT2|Designator=9|PinName_PositionConglomerate=16|Name_CustomFontID=1|PinDesignator_PositionConglomerate=16|Designator_CustomFontID=1|PinPropagationDelay=0.000000E+000
|RECORD=2|OwnerIndex=411|OwnerPartId=1|Electrical=1|PinConglomerate=58|PinLength=20|Location.X=1150|Location.Y=400|Name=C\S\|Designator=12|PinName_PositionConglomerate=16|Name_CustomFontID=1|PinDesignator_PositionConglomerate=16|Designator_CustomFontID=1|PinPropagationDelay=0.000000E+000
|RECORD=2|OwnerIndex=411|OwnerPartId=1|Electrical=1|PinConglomerate=58|PinLength=20|Location.X=1150|Location.Y=380|Name=SCX|Designator=13|PinName_PositionConglomerate=16|Name_CustomFontID=1|PinDesignator_PositionConglomerate=16|Designator_CustomFontID=1|PinPropagationDelay=0.000000E+000
|RECORD=2|OwnerIndex=411|OwnerPartId=1|Electrical=1|PinConglomerate=56|PinLength=20|Location.X=1270|Location.Y=400|Name=SDO|Designator=1|PinName_PositionConglomerate=16|Name_CustomFontID=1|PinDesignator_PositionConglomerate=16|Designator_CustomFontID=1|PinPropagationDelay=0.000000E+000
|RECORD=2|OwnerIndex=411|OwnerPartId=1|Electrical=1|PinConglomerate=56|PinLength=20|Location.X=1270|Location.Y=390|Name=SDX|Designator=14|PinName_PositionConglomerate=16|Name_CustomFontID=1|PinDesignator_PositionConglomerate=16|Designator_CustomFontID=1|PinPropagationDelay=0.000000E+000
|RECORD=2|OwnerIndex=411|OwnerPartId=1|Electrical=4|PinConglomerate=58|PinLength=20|Location.X=1150|Location.Y=350|Name=NC|Designator=10|PinName_PositionConglomerate=16|Name_CustomFontID=1|PinDesignator_PositionConglomerate=16|Designator_CustomFontID=1|PinPropagationDelay=0.000000E+000
|RECORD=2|OwnerIndex=411|OwnerPartId=1|Electrical=4|PinConglomerate=58|PinLength=20|Location.X=1150|Location.Y=360|Name=NC|Designator=11|PinName_PositionConglomerate=16|Name_CustomFontID=1|PinDesignator_PositionConglomerate=16|Designator_CustomFontID=1|PinPropagationDelay=0.000000E+000
|RECORD=2|OwnerIndex=411|OwnerPartId=1|Electrical=7|PinConglomerate=56|PinLength=20|Location.X=1270|Location.Y=370|Name=GND|Designator=2|PinName_PositionConglomerate=16|Name_CustomFontID=1|PinDesignator_PositionConglomerate=16|Designator_CustomFontID=1|PinPropagationDelay=0.000000E+000
|RECORD=2|OwnerIndex=411|OwnerPartId=1|Electrical=7|PinConglomerate=56|PinLength=20|Location.X=1270|Location.Y=360|Name=GND|Designator=3|PinName_PositionConglomerate=16|Name_CustomFontID=1|PinDesignator_PositionConglomerate=16|Designator_CustomFontID=1|PinPropagationDelay=0.000000E+000
|RECORD=2|OwnerIndex=411|OwnerPartId=1|Electrical=7|PinConglomerate=56|PinLength=20|Location.X=1270|Location.Y=350|Name=GND|Designator=7|PinName_PositionConglomerate=16|Name_CustomFontID=1|PinDesignator_PositionConglomerate=16|Designator_CustomFontID=1|PinPropagationDelay=0.000000E+000
|RECORD=2|OwnerIndex=411|OwnerPartId=1|Electrical=7|PinConglomerate=56|PinLength=20|Location.X=1270|Location.Y=340|Name=GNDIO|Designator=6|PinName_PositionConglomerate=16|Name_CustomFontID=1|PinDesignator_PositionConglomerate=16|Designator_CustomFontID=1|PinPropagationDelay=0.000000E+000
|RECORD=41|OwnerIndex=411|IndexInSheet=15|OwnerPartId=-1|Location.X=1128|Location.Y=440|Color=8388608|FontID=1|IsHidden=T|Text=14|Name=Number of Pins
|RECORD=41|OwnerIndex=411|IndexInSheet=16|OwnerPartId=-1|Location.X=1128|Location.Y=440|Color=8388608|FontID=1|IsHidden=T|Text=SPI|Name=Output Type
|RECORD=41|OwnerIndex=411|IndexInSheet=17|OwnerPartId=-1|Location.X=1128|Location.Y=440|Color=8388608|FontID=1|IsHidden=T|Text=85°C|Name=Max Operating Temperature
|RECORD=41|OwnerIndex=411|IndexInSheet=18|OwnerPartId=-1|Location.X=1128|Location.Y=440|Color=8388608|FontID=1|IsHidden=T|Text=Surface Mount|Name=Mount
|RECORD=41|OwnerIndex=411|IndexInSheet=19|OwnerPartId=-1|Location.X=1128|Location.Y=440|Color=8388608|FontID=1|IsHidden=T|Text=Accelerometer|Name=Sensor Type
|RECORD=41|OwnerIndex=411|IndexInSheet=20|OwnerPartId=-1|Location.X=1128|Location.Y=440|Color=8388608|FontID=1|IsHidden=T|Text=LGA|Name=Case/Package
|RECORD=41|OwnerIndex=411|IndexInSheet=21|OwnerPartId=-1|Location.X=1128|Location.Y=440|Color=8388608|FontID=1|IsHidden=T|Text=Tape and Reel|Name=Packaging
|RECORD=41|OwnerIndex=411|IndexInSheet=22|OwnerPartId=-1|Location.X=1128|Location.Y=440|Color=8388608|FontID=1|IsHidden=T|Text=-40°C|Name=Min Operating Temperature
|RECORD=34|OwnerIndex=411|IndexInSheet=-1|OwnerPartId=-1|Location.X=1150|Location.Y=440|Color=8388608|FontID=1|Text=U13|Name=Designator|ReadOnlyState=1
|RECORD=41|OwnerIndex=411|IndexInSheet=-1|OwnerPartId=1|Location.X=1150|Location.Y=320|Color=8388608|FontID=1|Text=BMX160|Name=Comment
|RECORD=44|OwnerIndex=411
|RECORD=45|OwnerIndex=451|IndexInSheet=-1|UseComponentLibrary=T|ModelName=FP-BMX160-MFG|ModelType=PCBLIB|DatafileCount=1|ModelDatafileEntity0=FP-BMX160-MFG|ModelDatafileKind0=PCBLib|IsCurrent=T|DatalinksLocked=T|DatabaseDatalinksLocked=T
|RECORD=46|OwnerIndex=452
|RECORD=48|OwnerIndex=452
|RECORD=1|LibReference=CAP|ComponentDescription=C0603X104K5RACAUTO|PartCount=2|DisplayModeCount=2|IndexInSheet=65|OwnerPartId=-1|Location.X=1080|Location.Y=300|Orientation=1|CurrentPartId=1|SourceLibraryName=Altium Content Vault|TargetFileName=*|AreaColor=11599871|Color=128|PartIDLocked=F|DesignItemId=CMP-2006-00003-1|AllPinCount=2
|RECORD=2|OwnerIndex=455|OwnerPartId=1|OwnerPartDisplayMode=1|FormalType=1|Electrical=4|PinConglomerate=35|PinLength=10|Location.X=1090|Location.Y=300|Name=1|Designator=1|PinPropagationDelay=0.000000E+000
|RECORD=2|OwnerIndex=455|OwnerPartId=1|OwnerPartDisplayMode=1|FormalType=1|Electrical=4|PinConglomerate=33|PinLength=10|Location.X=1090|Location.Y=310|Name=2|Designator=2|PinPropagationDelay=0.000000E+000
|RECORD=13|OwnerIndex=455|IsNotAccesible=T|IndexInSheet=2|OwnerPartId=1|OwnerPartDisplayMode=1|Location.X=1098|Location.Y=300|Corner.X=1082|Corner.Y=300|LineWidth=1|Color=16711680
|RECORD=13|OwnerIndex=455|IsNotAccesible=T|IndexInSheet=3|OwnerPartId=1|OwnerPartDisplayMode=1|Location.X=1090|Location.Y=304|Corner.X=1090|Corner.Y=310|LineWidth=1|Color=16711680
|RECORD=12|OwnerIndex=455|IsNotAccesible=T|IndexInSheet=4|OwnerPartId=1|OwnerPartDisplayMode=1|Location.X=1090|Location.Y=320|Radius=16|LineWidth=1|StartAngle=241.000|EndAngle=270.000|Color=16711680
|RECORD=12|OwnerIndex=455|IsNotAccesible=T|IndexInSheet=5|OwnerPartId=1|OwnerPartDisplayMode=1|Location.X=1090|Location.Y=320|Radius=16|LineWidth=1|StartAngle=270.000|EndAngle=299.000|Color=16711680
|RECORD=2|OwnerIndex=455|OwnerPartId=1|FormalType=1|Electrical=4|PinConglomerate=35|PinLength=10|Location.X=1090|Location.Y=300|Name=1|Designator=1|PinPropagationDelay=0.000000E+000
|RECORD=2|OwnerIndex=455|OwnerPartId=1|FormalType=1|Electrical=4|PinConglomerate=33|PinLength=10|Location.X=1090|Location.Y=310|Name=2|Designator=2|PinPropagationDelay=0.000000E+000
|RECORD=13|OwnerIndex=455|IsNotAccesible=T|IndexInSheet=8|OwnerPartId=1|Location.X=1082|Location.Y=307|Corner.X=1098|Corner.Y=307|LineWidth=1|Color=16711680
|RECORD=13|OwnerIndex=455|IsNotAccesible=T|IndexInSheet=9|OwnerPartId=1|Location.X=1098|Location.Y=303|Corner.X=1082|Corner.Y=303|LineWidth=1|Color=16711680
|RECORD=6|OwnerIndex=455|IsNotAccesible=T|IndexInSheet=10|OwnerPartId=1|LineWidth=1|Color=16711680|LocationCount=2|X1=1090|Y1=300|X2=1090|Y2=303
|RECORD=6|OwnerIndex=455|IsNotAccesible=T|IndexInSheet=11|OwnerPartId=1|LineWidth=1|Color=16711680|LocationCount=2|X1=1090|Y1=310|X2=1090|Y2=307
|RECORD=41|OwnerIndex=455|IndexInSheet=12|OwnerPartId=-1|Location.X=1081|Location.Y=322|Color=8388608|FontID=1|IsHidden=T|Text=Kemet|Name=Manufacturer
|RECORD=41|OwnerIndex=455|IndexInSheet=13|OwnerPartId=-1|Location.X=1081|Location.Y=322|Color=8388608|FontID=1|IsHidden=T|Text=C0603X104K5RACAUTO|Name=Part Number
|RECORD=34|OwnerIndex=455|IndexInSheet=-1|OwnerPartId=-1|Location.X=1099|Location.Y=301|Color=8388608|FontID=4|Text=C33|Name=Designator|ReadOnlyState=1
|RECORD=41|OwnerIndex=455|IndexInSheet=-1|OwnerPartId=-1|Location.X=1099|Location.Y=291|Color=8388608|FontID=4|Text=0.1uF|Name=Comment
|RECORD=44|OwnerIndex=455
|RECORD=45|OwnerIndex=476|IndexInSheet=-1|Description=Chip Capacitor, 2-Leads, Body 1.60x0.80mm, IPC Low Density|UseComponentLibrary=T|ModelName=CAPC1608X87X45ML20T05|ModelType=PCBLIB|DatafileCount=1|ModelDatafileEntity0=CAPC1608X87X45ML20T05|ModelDatafileKind0=PCBLib|IsCurrent=T|DatalinksLocked=T|DatabaseDatalinksLocked=T
|RECORD=46|OwnerIndex=477
|RECORD=48|OwnerIndex=477
|RECORD=41|OwnerIndex=479|IndexInSheet=-1|OwnerPartId=-1|Color=8388608|FontID=1|Text=2D|Name=Available Preview Images
|RECORD=45|OwnerIndex=476|IndexInSheet=-1|Description=Chip Capacitor, 2-Leads, Body 1.60x0.80mm, IPC High Density|UseComponentLibrary=T|ModelName=CAPC1608X87X45LL20T05|ModelType=PCBLIB|DatafileCount=1|ModelDatafileEntity0=CAPC1608X87X45LL20T05|ModelDatafileKind0=PCBLib|DatalinksLocked=T|DatabaseDatalinksLocked=T
|RECORD=46|OwnerIndex=481
|RECORD=48|OwnerIndex=481
|RECORD=41|OwnerIndex=483|IndexInSheet=-1|OwnerPartId=-1|Color=8388608|FontID=1|Text=2D|Name=Available Preview Images
|RECORD=45|OwnerIndex=476|IndexInSheet=-1|Description=Chip Capacitor, 2-Leads, Body 1.60x0.80mm, IPC Medium Density|UseComponentLibrary=T|ModelName=CAPC1608X87X45NL20T05|ModelType=PCBLIB|DatafileCount=1|ModelDatafileEntity0=CAPC1608X87X45NL20T05|ModelDatafileKind0=PCBLib|DatalinksLocked=T|DatabaseDatalinksLocked=T
|RECORD=46|OwnerIndex=485
|RECORD=48|OwnerIndex=485
|RECORD=41|OwnerIndex=487|IndexInSheet=-1|OwnerPartId=-1|Color=8388608|FontID=1|Text=2D|Name=Available Preview Images
|RECORD=22|IndexInSheet=66|OwnerPartId=-1|Location.X=1130|Location.Y=360|Color=255|Orientation=1|Symbol=Thin Cross|IsActive=T|SuppressAll=T
|RECORD=22|IndexInSheet=67|OwnerPartId=-1|Location.X=1130|Location.Y=350|Color=255|Orientation=1|Symbol=Thin Cross|IsActive=T|SuppressAll=T
|RECORD=1|LibReference=CAP|ComponentDescription=C0603X104K5RACAUTO|PartCount=2|DisplayModeCount=2|IndexInSheet=68|OwnerPartId=-1|Location.X=1030|Location.Y=300|Orientation=1|CurrentPartId=1|SourceLibraryName=Altium Content Vault|TargetFileName=*|AreaColor=11599871|Color=128|PartIDLocked=F|DesignItemId=CMP-2006-00003-1|AllPinCount=2
|RECORD=2|OwnerIndex=491|OwnerPartId=1|OwnerPartDisplayMode=1|FormalType=1|Electrical=4|PinConglomerate=35|PinLength=10|Location.X=1040|Location.Y=300|Name=1|Designator=1|PinPropagationDelay=0.000000E+000
|RECORD=2|OwnerIndex=491|OwnerPartId=1|OwnerPartDisplayMode=1|FormalType=1|Electrical=4|PinConglomerate=33|PinLength=10|Location.X=1040|Location.Y=310|Name=2|Designator=2|PinPropagationDelay=0.000000E+000
|RECORD=13|OwnerIndex=491|IsNotAccesible=T|IndexInSheet=2|OwnerPartId=1|OwnerPartDisplayMode=1|Location.X=1048|Location.Y=300|Corner.X=1032|Corner.Y=300|LineWidth=1|Color=16711680
|RECORD=13|OwnerIndex=491|IsNotAccesible=T|IndexInSheet=3|OwnerPartId=1|OwnerPartDisplayMode=1|Location.X=1040|Location.Y=304|Corner.X=1040|Corner.Y=310|LineWidth=1|Color=16711680
|RECORD=12|OwnerIndex=491|IsNotAccesible=T|IndexInSheet=4|OwnerPartId=1|OwnerPartDisplayMode=1|Location.X=1040|Location.Y=320|Radius=16|LineWidth=1|StartAngle=241.000|EndAngle=270.000|Color=16711680
|RECORD=12|OwnerIndex=491|IsNotAccesible=T|IndexInSheet=5|OwnerPartId=1|OwnerPartDisplayMode=1|Location.X=1040|Location.Y=320|Radius=16|LineWidth=1|StartAngle=270.000|EndAngle=299.000|Color=16711680
|RECORD=2|OwnerIndex=491|OwnerPartId=1|FormalType=1|Electrical=4|PinConglomerate=35|PinLength=10|Location.X=1040|Location.Y=300|Name=1|Designator=1|PinPropagationDelay=0.000000E+000
|RECORD=2|OwnerIndex=491|OwnerPartId=1|FormalType=1|Electrical=4|PinConglomerate=33|PinLength=10|Location.X=1040|Location.Y=310|Name=2|Designator=2|PinPropagationDelay=0.000000E+000
|RECORD=13|OwnerIndex=491|IsNotAccesible=T|IndexInSheet=8|OwnerPartId=1|Location.X=1032|Location.Y=307|Corner.X=1048|Corner.Y=307|LineWidth=1|Color=16711680
|RECORD=13|OwnerIndex=491|IsNotAccesible=T|IndexInSheet=9|OwnerPartId=1|Location.X=1048|Location.Y=303|Corner.X=1032|Corner.Y=303|LineWidth=1|Color=16711680
|RECORD=6|OwnerIndex=491|IsNotAccesible=T|IndexInSheet=10|OwnerPartId=1|LineWidth=1|Color=16711680|LocationCount=2|X1=1040|Y1=300|X2=1040|Y2=303
|RECORD=6|OwnerIndex=491|IsNotAccesible=T|IndexInSheet=11|OwnerPartId=1|LineWidth=1|Color=16711680|LocationCount=2|X1=1040|Y1=310|X2=1040|Y2=307
|RECORD=41|OwnerIndex=491|IndexInSheet=12|OwnerPartId=-1|Location.X=1031|Location.Y=322|Color=8388608|FontID=1|IsHidden=T|Text=Kemet|Name=Manufacturer
|RECORD=41|OwnerIndex=491|IndexInSheet=13|OwnerPartId=-1|Location.X=1031|Location.Y=322|Color=8388608|FontID=1|IsHidden=T|Text=C0603X104K5RACAUTO|Name=Part Number
|RECORD=34|OwnerIndex=491|IndexInSheet=-1|OwnerPartId=-1|Location.X=1049|Location.Y=301|Color=8388608|FontID=4|Text=C32|Name=Designator|ReadOnlyState=1
|RECORD=41|OwnerIndex=491|IndexInSheet=-1|OwnerPartId=-1|Location.X=1049|Location.Y=291|Color=8388608|FontID=4|Text=0.1uF|Name=Comment
|RECORD=44|OwnerIndex=491
|RECORD=45|OwnerIndex=512|IndexInSheet=-1|Description=Chip Capacitor, 2-Leads, Body 1.60x0.80mm, IPC Low Density|UseComponentLibrary=T|ModelName=CAPC1608X87X45ML20T05|ModelType=PCBLIB|DatafileCount=1|ModelDatafileEntity0=CAPC1608X87X45ML20T05|ModelDatafileKind0=PCBLib|IsCurrent=T|DatalinksLocked=T|DatabaseDatalinksLocked=T
|RECORD=46|OwnerIndex=513
|RECORD=48|OwnerIndex=513
|RECORD=41|OwnerIndex=515|IndexInSheet=-1|OwnerPartId=-1|Color=8388608|FontID=1|Text=2D|Name=Available Preview Images
|RECORD=45|OwnerIndex=512|IndexInSheet=-1|Description=Chip Capacitor, 2-Leads, Body 1.60x0.80mm, IPC High Density|UseComponentLibrary=T|ModelName=CAPC1608X87X45LL20T05|ModelType=PCBLIB|DatafileCount=1|ModelDatafileEntity0=CAPC1608X87X45LL20T05|ModelDatafileKind0=PCBLib|DatalinksLocked=T|DatabaseDatalinksLocked=T
|RECORD=46|OwnerIndex=517
|RECORD=48|OwnerIndex=517
|RECORD=41|OwnerIndex=519|IndexInSheet=-1|OwnerPartId=-1|Color=8388608|FontID=1|Text=2D|Name=Available Preview Images
|RECORD=45|OwnerIndex=512|IndexInSheet=-1|Description=Chip Capacitor, 2-Leads, Body 1.60x0.80mm, IPC Medium Density|UseComponentLibrary=T|ModelName=CAPC1608X87X45NL20T05|ModelType=PCBLIB|DatafileCount=1|ModelDatafileEntity0=CAPC1608X87X45NL20T05|ModelDatafileKind0=PCBLib|DatalinksLocked=T|DatabaseDatalinksLocked=T
|RECORD=46|OwnerIndex=521
|RECORD=48|OwnerIndex=521
|RECORD=41|OwnerIndex=523|IndexInSheet=-1|OwnerPartId=-1|Color=8388608|FontID=1|Text=2D|Name=Available Preview Images
|RECORD=17|IndexInSheet=69|OwnerPartId=-1|Style=4|ShowNetName=T|Location.X=1090|Location.Y=270|Orientation=3|Color=128|FontID=1|Text=GND
|RECORD=17|IndexInSheet=70|OwnerPartId=-1|Style=4|ShowNetName=T|Location.X=1040|Location.Y=270|Orientation=3|Color=128|FontID=1|Text=GND
|RECORD=17|IndexInSheet=71|OwnerPartId=-1|Style=4|ShowNetName=T|Location.X=1350|Location.Y=270|Orientation=3|Color=128|FontID=1|Text=GND
|RECORD=17|IndexInSheet=72|OwnerPartId=-1|ShowNetName=T|Location.X=1420|Location.Y=390|Color=255|FontID=1|Text=SDA|IsCrossSheetConnector=T
|RECORD=17|IndexInSheet=73|OwnerPartId=-1|ShowNetName=T|Location.X=1010|Location.Y=380|Orientation=2|Color=255|FontID=1|Text=SCL|IsCrossSheetConnector=T
|RECORD=17|IndexInSheet=74|OwnerPartId=-1|ShowNetName=T|Location.X=1000|Location.Y=490|Orientation=1|Color=128|FontID=1|Text=+3.3V
|RECORD=17|IndexInSheet=75|OwnerPartId=-1|ShowNetName=T|Location.X=1040|Location.Y=490|Orientation=1|Color=128|FontID=1|Text=+3.3V
|RECORD=17|IndexInSheet=76|OwnerPartId=-1|ShowNetName=T|Location.X=1090|Location.Y=490|Orientation=1|Color=128|FontID=1|Text=+3.3V
|RECORD=22|IndexInSheet=77|OwnerPartId=-1|Location.X=1290|Location.Y=430|Color=255|Orientation=1|Symbol=Thin Cross|IsActive=T|SuppressAll=T
|RECORD=22|IndexInSheet=78|OwnerPartId=-1|Location.X=1290|Location.Y=420|Color=255|Orientation=1|Symbol=Thin Cross|IsActive=T|SuppressAll=T
|RECORD=17|IndexInSheet=79|OwnerPartId=-1|Style=4|ShowNetName=T|Location.X=1390|Location.Y=270|Orientation=3|Color=128|FontID=1|Text=GND
|RECORD=17|IndexInSheet=80|OwnerPartId=-1|Style=4|ShowNetName=T|Location.X=440|Location.Y=270|Orientation=3|Color=128|FontID=1|Text=GND
|RECORD=17|IndexInSheet=81|OwnerPartId=-1|Style=4|ShowNetName=T|Location.X=390|Location.Y=270|Orientation=3|Color=128|FontID=1|Text=GND
|RECORD=1|LibReference=CAP|ComponentDescription=C0603X104K5RACAUTO|PartCount=2|DisplayModeCount=2|IndexInSheet=82|OwnerPartId=-1|Location.X=430|Location.Y=300|Orientation=1|CurrentPartId=1|SourceLibraryName=Altium Content Vault|TargetFileName=*|AreaColor=11599871|Color=128|PartIDLocked=F|DesignItemId=CMP-2006-00003-1|AllPinCount=2
|RECORD=2|OwnerIndex=538|OwnerPartId=1|OwnerPartDisplayMode=1|FormalType=1|Electrical=4|PinConglomerate=35|PinLength=10|Location.X=440|Location.Y=300|Name=1|Designator=1|PinPropagationDelay=0.000000E+000
|RECORD=2|OwnerIndex=538|OwnerPartId=1|OwnerPartDisplayMode=1|FormalType=1|Electrical=4|PinConglomerate=33|PinLength=10|Location.X=440|Location.Y=310|Name=2|Designator=2|PinPropagationDelay=0.000000E+000
|RECORD=13|OwnerIndex=538|IsNotAccesible=T|IndexInSheet=2|OwnerPartId=1|OwnerPartDisplayMode=1|Location.X=448|Location.Y=300|Corner.X=432|Corner.Y=300|LineWidth=1|Color=16711680
|RECORD=13|OwnerIndex=538|IsNotAccesible=T|IndexInSheet=3|OwnerPartId=1|OwnerPartDisplayMode=1|Location.X=440|Location.Y=304|Corner.X=440|Corner.Y=310|LineWidth=1|Color=16711680
|RECORD=12|OwnerIndex=538|IsNotAccesible=T|IndexInSheet=4|OwnerPartId=1|OwnerPartDisplayMode=1|Location.X=440|Location.Y=320|Radius=16|LineWidth=1|StartAngle=241.000|EndAngle=270.000|Color=16711680
|RECORD=12|OwnerIndex=538|IsNotAccesible=T|IndexInSheet=5|OwnerPartId=1|OwnerPartDisplayMode=1|Location.X=440|Location.Y=320|Radius=16|LineWidth=1|StartAngle=270.000|EndAngle=299.000|Color=16711680
|RECORD=2|OwnerIndex=538|OwnerPartId=1|FormalType=1|Electrical=4|PinConglomerate=35|PinLength=10|Location.X=440|Location.Y=300|Name=1|Designator=1|PinPropagationDelay=0.000000E+000
|RECORD=2|OwnerIndex=538|OwnerPartId=1|FormalType=1|Electrical=4|PinConglomerate=33|PinLength=10|Location.X=440|Location.Y=310|Name=2|Designator=2|PinPropagationDelay=0.000000E+000
|RECORD=13|OwnerIndex=538|IsNotAccesible=T|IndexInSheet=8|OwnerPartId=1|Location.X=432|Location.Y=307|Corner.X=448|Corner.Y=307|LineWidth=1|Color=16711680
|RECORD=13|OwnerIndex=538|IsNotAccesible=T|IndexInSheet=9|OwnerPartId=1|Location.X=448|Location.Y=303|Corner.X=432|Corner.Y=303|LineWidth=1|Color=16711680
|RECORD=6|OwnerIndex=538|IsNotAccesible=T|IndexInSheet=10|OwnerPartId=1|LineWidth=1|Color=16711680|LocationCount=2|X1=440|Y1=300|X2=440|Y2=303
|RECORD=6|OwnerIndex=538|IsNotAccesible=T|IndexInSheet=11|OwnerPartId=1|LineWidth=1|Color=16711680|LocationCount=2|X1=440|Y1=310|X2=440|Y2=307
|RECORD=41|OwnerIndex=538|IndexInSheet=12|OwnerPartId=-1|Location.X=431|Location.Y=322|Color=8388608|FontID=1|IsHidden=T|Text=Kemet|Name=Manufacturer
|RECORD=41|OwnerIndex=538|IndexInSheet=13|OwnerPartId=-1|Location.X=431|Location.Y=322|Color=8388608|FontID=1|IsHidden=T|Text=C0603X104K5RACAUTO|Name=Part Number
|RECORD=34|OwnerIndex=538|IndexInSheet=-1|OwnerPartId=-1|Location.X=449|Location.Y=301|Color=8388608|FontID=4|Text=C31|Name=Designator|ReadOnlyState=1
|RECORD=41|OwnerIndex=538|IndexInSheet=-1|OwnerPartId=-1|Location.X=449|Location.Y=291|Color=8388608|FontID=4|Text=0.1uF|Name=Comment
|RECORD=44|OwnerIndex=538
|RECORD=45|OwnerIndex=559|IndexInSheet=-1|Description=Chip Capacitor, 2-Leads, Body 1.60x0.80mm, IPC Low Density|UseComponentLibrary=T|ModelName=CAPC1608X87X45ML20T05|ModelType=PCBLIB|DatafileCount=1|ModelDatafileEntity0=CAPC1608X87X45ML20T05|ModelDatafileKind0=PCBLib|IsCurrent=T|DatalinksLocked=T|DatabaseDatalinksLocked=T
|RECORD=46|OwnerIndex=560
|RECORD=48|OwnerIndex=560
|RECORD=41|OwnerIndex=562|IndexInSheet=-1|OwnerPartId=-1|Color=8388608|FontID=1|Text=2D|Name=Available Preview Images
|RECORD=45|OwnerIndex=559|IndexInSheet=-1|Description=Chip Capacitor, 2-Leads, Body 1.60x0.80mm, IPC High Density|UseComponentLibrary=T|ModelName=CAPC1608X87X45LL20T05|ModelType=PCBLIB|DatafileCount=1|ModelDatafileEntity0=CAPC1608X87X45LL20T05|ModelDatafileKind0=PCBLib|DatalinksLocked=T|DatabaseDatalinksLocked=T
|RECORD=46|OwnerIndex=564
|RECORD=48|OwnerIndex=564
|RECORD=41|OwnerIndex=566|IndexInSheet=-1|OwnerPartId=-1|Color=8388608|FontID=1|Text=2D|Name=Available Preview Images
|RECORD=45|OwnerIndex=559|IndexInSheet=-1|Description=Chip Capacitor, 2-Leads, Body 1.60x0.80mm, IPC Medium Density|UseComponentLibrary=T|ModelName=CAPC1608X87X45NL20T05|ModelType=PCBLIB|DatafileCount=1|ModelDatafileEntity0=CAPC1608X87X45NL20T05|ModelDatafileKind0=PCBLib|DatalinksLocked=T|DatabaseDatalinksLocked=T
|RECORD=46|OwnerIndex=568
|RECORD=48|OwnerIndex=568
|RECORD=41|OwnerIndex=570|IndexInSheet=-1|OwnerPartId=-1|Color=8388608|FontID=1|Text=2D|Name=Available Preview Images
|RECORD=1|LibReference=CAP|ComponentDescription=C0603X104K5RACAUTO|PartCount=2|DisplayModeCount=2|IndexInSheet=83|OwnerPartId=-1|Location.X=380|Location.Y=300|Orientation=1|CurrentPartId=1|SourceLibraryName=Altium Content Vault|TargetFileName=*|AreaColor=11599871|Color=128|PartIDLocked=F|DesignItemId=CMP-2006-00003-1|AllPinCount=2
|RECORD=2|OwnerIndex=572|OwnerPartId=1|OwnerPartDisplayMode=1|FormalType=1|Electrical=4|PinConglomerate=35|PinLength=10|Location.X=390|Location.Y=300|Name=1|Designator=1|PinPropagationDelay=0.000000E+000
|RECORD=2|OwnerIndex=572|OwnerPartId=1|OwnerPartDisplayMode=1|FormalType=1|Electrical=4|PinConglomerate=33|PinLength=10|Location.X=390|Location.Y=310|Name=2|Designator=2|PinPropagationDelay=0.000000E+000
|RECORD=13|OwnerIndex=572|IsNotAccesible=T|IndexInSheet=2|OwnerPartId=1|OwnerPartDisplayMode=1|Location.X=398|Location.Y=300|Corner.X=382|Corner.Y=300|LineWidth=1|Color=16711680
|RECORD=13|OwnerIndex=572|IsNotAccesible=T|IndexInSheet=3|OwnerPartId=1|OwnerPartDisplayMode=1|Location.X=390|Location.Y=304|Corner.X=390|Corner.Y=310|LineWidth=1|Color=16711680
|RECORD=12|OwnerIndex=572|IsNotAccesible=T|IndexInSheet=4|OwnerPartId=1|OwnerPartDisplayMode=1|Location.X=390|Location.Y=320|Radius=16|LineWidth=1|StartAngle=241.000|EndAngle=270.000|Color=16711680
|RECORD=12|OwnerIndex=572|IsNotAccesible=T|IndexInSheet=5|OwnerPartId=1|OwnerPartDisplayMode=1|Location.X=390|Location.Y=320|Radius=16|LineWidth=1|StartAngle=270.000|EndAngle=299.000|Color=16711680
|RECORD=2|OwnerIndex=572|OwnerPartId=1|FormalType=1|Electrical=4|PinConglomerate=35|PinLength=10|Location.X=390|Location.Y=300|Name=1|Designator=1|PinPropagationDelay=0.000000E+000
|RECORD=2|OwnerIndex=572|OwnerPartId=1|FormalType=1|Electrical=4|PinConglomerate=33|PinLength=10|Location.X=390|Location.Y=310|Name=2|Designator=2|PinPropagationDelay=0.000000E+000
|RECORD=13|OwnerIndex=572|IsNotAccesible=T|IndexInSheet=8|OwnerPartId=1|Location.X=382|Location.Y=307|Corner.X=398|Corner.Y=307|LineWidth=1|Color=16711680
|RECORD=13|OwnerIndex=572|IsNotAccesible=T|IndexInSheet=9|OwnerPartId=1|Location.X=398|Location.Y=303|Corner.X=382|Corner.Y=303|LineWidth=1|Color=16711680
|RECORD=6|OwnerIndex=572|IsNotAccesible=T|IndexInSheet=10|OwnerPartId=1|LineWidth=1|Color=16711680|LocationCount=2|X1=390|Y1=300|X2=390|Y2=303
|RECORD=6|OwnerIndex=572|IsNotAccesible=T|IndexInSheet=11|OwnerPartId=1|LineWidth=1|Color=16711680|LocationCount=2|X1=390|Y1=310|X2=390|Y2=307
|RECORD=41|OwnerIndex=572|IndexInSheet=12|OwnerPartId=-1|Location.X=381|Location.Y=322|Color=8388608|FontID=1|IsHidden=T|Text=Kemet|Name=Manufacturer
|RECORD=41|OwnerIndex=572|IndexInSheet=13|OwnerPartId=-1|Location.X=381|Location.Y=322|Color=8388608|FontID=1|IsHidden=T|Text=C0603X104K5RACAUTO|Name=Part Number
|RECORD=34|OwnerIndex=572|IndexInSheet=-1|OwnerPartId=-1|Location.X=399|Location.Y=301|Color=8388608|FontID=4|Text=C30|Name=Designator|ReadOnlyState=1
|RECORD=41|OwnerIndex=572|IndexInSheet=-1|OwnerPartId=-1|Location.X=399|Location.Y=291|Color=8388608|FontID=4|Text=0.1uF|Name=Comment
|RECORD=44|OwnerIndex=572
|RECORD=45|OwnerIndex=593|IndexInSheet=-1|Description=Chip Capacitor, 2-Leads, Body 1.60x0.80mm, IPC Low Density|UseComponentLibrary=T|ModelName=CAPC1608X87X45ML20T05|ModelType=PCBLIB|DatafileCount=1|ModelDatafileEntity0=CAPC1608X87X45ML20T05|ModelDatafileKind0=PCBLib|IsCurrent=T|DatalinksLocked=T|DatabaseDatalinksLocked=T
|RECORD=46|OwnerIndex=594
|RECORD=48|OwnerIndex=594
|RECORD=41|OwnerIndex=596|IndexInSheet=-1|OwnerPartId=-1|Color=8388608|FontID=1|Text=2D|Name=Available Preview Images
|RECORD=45|OwnerIndex=593|IndexInSheet=-1|Description=Chip Capacitor, 2-Leads, Body 1.60x0.80mm, IPC High Density|UseComponentLibrary=T|ModelName=CAPC1608X87X45LL20T05|ModelType=PCBLIB|DatafileCount=1|ModelDatafileEntity0=CAPC1608X87X45LL20T05|ModelDatafileKind0=PCBLib|DatalinksLocked=T|DatabaseDatalinksLocked=T
|RECORD=46|OwnerIndex=598
|RECORD=48|OwnerIndex=598
|RECORD=41|OwnerIndex=600|IndexInSheet=-1|OwnerPartId=-1|Color=8388608|FontID=1|Text=2D|Name=Available Preview Images
|RECORD=45|OwnerIndex=593|IndexInSheet=-1|Description=Chip Capacitor, 2-Leads, Body 1.60x0.80mm, IPC Medium Density|UseComponentLibrary=T|ModelName=CAPC1608X87X45NL20T05|ModelType=PCBLIB|DatafileCount=1|ModelDatafileEntity0=CAPC1608X87X45NL20T05|ModelDatafileKind0=PCBLib|DatalinksLocked=T|DatabaseDatalinksLocked=T
|RECORD=46|OwnerIndex=602
|RECORD=48|OwnerIndex=602
|RECORD=41|OwnerIndex=604|IndexInSheet=-1|OwnerPartId=-1|Color=8388608|FontID=1|Text=2D|Name=Available Preview Images
|RECORD=17|IndexInSheet=84|OwnerPartId=-1|ShowNetName=T|Location.X=440|Location.Y=470|Orientation=1|Color=128|FontID=1|Text=+3.3V
|RECORD=17|IndexInSheet=85|OwnerPartId=-1|ShowNetName=T|Location.X=390|Location.Y=470|Orientation=1|Color=128|FontID=1|Text=+3.3V
|RECORD=17|IndexInSheet=86|OwnerPartId=-1|ShowNetName=T|Location.X=690|Location.Y=420|Color=255|FontID=1|Text=SCL|IsCrossSheetConnector=T
|RECORD=17|IndexInSheet=87|OwnerPartId=-1|ShowNetName=T|Location.X=690|Location.Y=410|Color=255|FontID=1|Text=SDA|IsCrossSheetConnector=T
|RECORD=17|IndexInSheet=88|OwnerPartId=-1|ShowNetName=T|Location.X=650|Location.Y=470|Orientation=1|Color=128|FontID=1|Text=+3.3V
|RECORD=17|IndexInSheet=89|OwnerPartId=-1|Style=4|ShowNetName=T|Location.X=650|Location.Y=270|Orientation=3|Color=128|FontID=1|Text=GND
|RECORD=17|IndexInSheet=90|OwnerPartId=-1|Style=4|ShowNetName=T|Location.X=690|Location.Y=270|Orientation=3|Color=128|FontID=1|Text=GND
|RECORD=4|IndexInSheet=91|OwnerPartId=-1|Location.X=440|Location.Y=530|Color=8388608|FontID=5|Text=ENVIRONMENT (0x76)
|RECORD=4|IndexInSheet=92|OwnerPartId=-1|Location.X=1150|Location.Y=530|Color=8388608|FontID=5|Text=IMU (0x68)
|RECORD=17|IndexInSheet=93|OwnerPartId=-1|ShowNetName=T|Location.X=250|Location.Y=500|Orientation=3|Color=255|FontID=1|Text=SCL|IsCrossSheetConnector=T
|RECORD=17|IndexInSheet=94|OwnerPartId=-1|ShowNetName=T|Location.X=200|Location.Y=500|Orientation=3|Color=255|FontID=1|Text=SDA|IsCrossSheetConnector=T
|RECORD=17|IndexInSheet=95|OwnerPartId=-1|ShowNetName=T|Location.X=250|Location.Y=610|Orientation=1|Color=128|FontID=1|Text=+3.3V
|RECORD=17|IndexInSheet=96|OwnerPartId=-1|ShowNetName=T|Location.X=200|Location.Y=610|Orientation=1|Color=128|FontID=1|Text=+3.3V
|RECORD=1|LibReference=RES-2|ComponentDescription=Precision Thick Film Chip Resistor, 4.7 KOhm, +/- 1%, -55 to 155 degC, 0603 (1608 Metric), RoHS, Tape and Reel ERJ-3EKF4701V|PartCount=2|DisplayModeCount=1|IndexInSheet=97|OwnerPartId=-1|Location.X=250|Location.Y=550|Orientation=1|CurrentPartId=1|LibraryPath=*|SourceLibraryName=Altium Content Vault|TargetFileName=*|AreaColor=11599871|Color=128|PartIDLocked=T|DesignItemId=CMP-1012-00586-3|AllPinCount=2
|RECORD=2|OwnerIndex=619|OwnerPartId=1|FormalType=1|Electrical=4|PinConglomerate=33|PinLength=10|Location.X=250|Location.Y=570|Name=2|Designator=2|PinPropagationDelay=0.000000E+000
|RECORD=2|OwnerIndex=619|OwnerPartId=1|FormalType=1|Electrical=4|PinConglomerate=35|PinLength=10|Location.X=250|Location.Y=550|Name=1|Designator=1|PinPropagationDelay=0.000000E+000
|RECORD=6|OwnerIndex=619|IsNotAccesible=T|IndexInSheet=2|OwnerPartId=1|LineWidth=1|Color=16711680|LocationCount=10|X1=250|Y1=570|X2=250|Y2=566|X3=252|Y3=565|X4=248|Y4=563|X5=252|Y5=561|X6=248|Y6=559|X7=252|Y7=557|X8=248|Y8=555|X9=250|Y9=554|X10=250|Y10=550
|RECORD=41|OwnerIndex=619|IndexInSheet=3|OwnerPartId=-1|Location.X=247|Location.Y=582|Color=8388608|FontID=1|IsHidden=T|Text=220 Ohm|Name=Resistance
|RECORD=41|OwnerIndex=619|IndexInSheet=4|OwnerPartId=-1|Location.X=247|Location.Y=582|Color=8388608|FontID=1|IsHidden=T|Text=0603|Name=PackageReference
|RECORD=41|OwnerIndex=619|IndexInSheet=5|OwnerPartId=-1|Location.X=247|Location.Y=582|Color=8388608|FontID=1|IsHidden=T|Text=50 V|Name=Voltage Rating
|RECORD=41|OwnerIndex=619|IndexInSheet=6|OwnerPartId=-1|Location.X=247|Location.Y=582|Color=8388608|FontID=1|IsHidden=T|Text=125 degC|Name=Max Operating Temperature
|RECORD=41|OwnerIndex=619|IndexInSheet=7|OwnerPartId=-1|Location.X=247|Location.Y=582|Color=8388608|FontID=1|IsHidden=T|Text=4|Name=Elements
|RECORD=41|OwnerIndex=619|IndexInSheet=8|OwnerPartId=-1|Location.X=247|Location.Y=582|Color=8388608|FontID=1|IsHidden=T|Text=No SVHC|Name=REACH SVHC
|RECORD=41|OwnerIndex=619|IndexInSheet=9|OwnerPartId=-1|Location.X=247|Location.Y=582|Color=8388608|FontID=1|IsHidden=T|Text=0.063 inch|Name=Width
|RECORD=41|OwnerIndex=619|IndexInSheet=10|OwnerPartId=-1|Location.X=247|Location.Y=582|Color=8388608|FontID=1|IsHidden=T|Text=1205|Name=Case\Package
|RECORD=41|OwnerIndex=619|IndexInSheet=11|OwnerPartId=-1|Location.X=247|Location.Y=582|Color=8388608|FontID=1|IsHidden=T|Text=0.126 inch|Name=Length
|RECORD=41|OwnerIndex=619|IndexInSheet=12|OwnerPartId=-1|Location.X=247|Location.Y=582|Color=8388608|FontID=1|IsHidden=T|Text=0.024 inch|Name=Height
|RECORD=41|OwnerIndex=619|IndexInSheet=13|OwnerPartId=-1|Location.X=247|Location.Y=582|Color=8388608|FontID=1|IsHidden=T|Text=Surface Mount|Name=Mount
|RECORD=41|OwnerIndex=619|IndexInSheet=14|OwnerPartId=-1|Location.X=247|Location.Y=582|Color=8388608|FontID=1|IsHidden=T|Text=1|Name=Package Quantity
|RECORD=41|OwnerIndex=619|IndexInSheet=15|OwnerPartId=-1|Location.X=247|Location.Y=582|Color=8388608|FontID=1|IsHidden=T|Text=Apr-15|Name=DatasheetVersion
|RECORD=41|OwnerIndex=619|IndexInSheet=16|OwnerPartId=-1|Location.X=247|Location.Y=582|Color=8388608|FontID=1|IsHidden=T|Text=Manufacturer URL|Name=ComponentLink1Description
|RECORD=41|OwnerIndex=619|IndexInSheet=17|OwnerPartId=-1|Location.X=247|Location.Y=582|Color=8388608|FontID=1|IsHidden=T|Text=-55 degC|Name=Min Operating Temperature
|RECORD=41|OwnerIndex=619|IndexInSheet=18|OwnerPartId=-1|Location.X=247|Location.Y=582|Color=8388608|FontID=1|IsHidden=T|Text=Tape and Reel|Name=Packaging
|RECORD=41|OwnerIndex=619|IndexInSheet=19|OwnerPartId=-1|Location.X=247|Location.Y=582|Color=8388608|FontID=1|IsHidden=T|Text=No|Name=Radiation Hardening
|RECORD=41|OwnerIndex=619|IndexInSheet=20|OwnerPartId=-1|Location.X=247|Location.Y=582|Color=8388608|FontID=2|IsHidden=T|Text=http://industrial.panasonic.com/cdbs/www-data/pdf/RDA0000/AOA0000C86.pdf|Name=ComponentLink2URL
|RECORD=41|OwnerIndex=619|IndexInSheet=21|OwnerPartId=-1|Location.X=247|Location.Y=582|Color=8388608|FontID=1|IsHidden=T|Text=3216|Name=Case Code (Metric)
|RECORD=41|OwnerIndex=619|IndexInSheet=22|OwnerPartId=-1|Location.X=247|Location.Y=582|Color=8388608|FontID=1|IsHidden=T|Text=8|Name=Pins
|RECORD=41|OwnerIndex=619|IndexInSheet=23|OwnerPartId=-1|Location.X=247|Location.Y=582|Color=8388608|FontID=1|IsHidden=T|Text=1206|Name=Case Code (Imperial)
|RECORD=41|OwnerIndex=619|IndexInSheet=24|OwnerPartId=-1|Location.X=247|Location.Y=582|Color=8388608|FontID=1|IsHidden=T|Text=Thick Film|Name=Type (Resistor)
|RECORD=41|OwnerIndex=619|IndexInSheet=25|OwnerPartId=-1|Location.X=247|Location.Y=582|Color=8388608|FontID=1|IsHidden=T|Text=true|Name=RoHSCompliant
|RECORD=41|OwnerIndex=619|IndexInSheet=26|OwnerPartId=-1|Location.X=247|Location.Y=582|Color=8388608|FontID=1|IsHidden=T|Text=5%|Name=Tolerance
|RECORD=41|OwnerIndex=619|IndexInSheet=27|OwnerPartId=-1|Location.X=247|Location.Y=582|Color=8388608|FontID=1|IsHidden=T|Text=Datasheet|Name=ComponentLink2Description
|RECORD=41|OwnerIndex=619|IndexInSheet=28|OwnerPartId=-1|Location.X=247|Location.Y=582|Color=8388608|FontID=1|IsHidden=T|Text=2-Pin Surface Mount Device, Body 1.6 x 0.85 mm|Name=PackageDescription
|RECORD=41|OwnerIndex=619|IndexInSheet=29|OwnerPartId=-1|Location.X=247|Location.Y=582|Color=8388608|FontID=2|IsHidden=T|Text=http://www.panasonic.com/|Name=ComponentLink1URL
|RECORD=41|OwnerIndex=619|IndexInSheet=30|OwnerPartId=-1|Location.X=247|Location.Y=582|Color=8388608|FontID=1|IsHidden=T|Text=250 mW|Name=Power Rating
|RECORD=34|OwnerIndex=619|IndexInSheet=-1|OwnerPartId=-1|Location.X=253|Location.Y=561|Color=8388608|FontID=1|Text=R27|Name=Designator|ReadOnlyState=1
|RECORD=41|OwnerIndex=619|IndexInSheet=-1|OwnerPartId=-1|Location.X=253|Location.Y=551|Color=8388608|FontID=1|Text=4.7K|Name=Comment
|RECORD=44|OwnerIndex=619
|RECORD=45|OwnerIndex=655|IndexInSheet=-1|Description=Chip Resistor, 2-Leads, Body 1.75x0.95mm, IPC Medium Density|UseComponentLibrary=T|ModelName=RESC1608X55X30NL15T15|ModelType=PCBLIB|IsCurrent=T|DatalinksLocked=T|DatabaseDatalinksLocked=T
|RECORD=46|OwnerIndex=656
|RECORD=48|OwnerIndex=656
|RECORD=41|OwnerIndex=658|IndexInSheet=-1|OwnerPartId=-1|Color=8388608|FontID=1|IsHidden=T|Text=2D|Name=Available Preview Images
|RECORD=45|OwnerIndex=655|IndexInSheet=-1|Description=Chip Resistor, 2-Leads, Body 1.75x0.95mm, IPC Low Density|UseComponentLibrary=T|ModelName=RESC1608X55X30ML15T15|ModelType=PCBLIB|DatalinksLocked=T|DatabaseDatalinksLocked=T
|RECORD=46|OwnerIndex=660
|RECORD=48|OwnerIndex=660
|RECORD=41|OwnerIndex=662|IndexInSheet=-1|OwnerPartId=-1|Color=8388608|FontID=1|IsHidden=T|Text=2D|Name=Available Preview Images
|RECORD=45|OwnerIndex=655|IndexInSheet=-1|Description=Chip Resistor, 2-Leads, Body 1.75x0.95mm, IPC High Density|UseComponentLibrary=T|ModelName=RESC1608X55X30LL15T15|ModelType=PCBLIB|DatalinksLocked=T|DatabaseDatalinksLocked=T
|RECORD=46|OwnerIndex=664
|RECORD=48|OwnerIndex=664
|RECORD=41|OwnerIndex=666|IndexInSheet=-1|OwnerPartId=-1|Color=8388608|FontID=1|IsHidden=T|Text=2D|Name=Available Preview Images
|RECORD=1|LibReference=RES-2|ComponentDescription=Precision Thick Film Chip Resistor, 4.7 KOhm, +/- 1%, -55 to 155 degC, 0603 (1608 Metric), RoHS, Tape and Reel ERJ-3EKF4701V|PartCount=2|DisplayModeCount=1|IndexInSheet=98|OwnerPartId=-1|Location.X=200|Location.Y=550|Orientation=1|CurrentPartId=1|LibraryPath=*|SourceLibraryName=Altium Content Vault|TargetFileName=*|AreaColor=11599871|Color=128|PartIDLocked=T|DesignItemId=CMP-1012-00586-3|AllPinCount=2
|RECORD=2|OwnerIndex=668|OwnerPartId=1|FormalType=1|Electrical=4|PinConglomerate=33|PinLength=10|Location.X=200|Location.Y=570|Name=2|Designator=2|PinPropagationDelay=0.000000E+000
|RECORD=2|OwnerIndex=668|OwnerPartId=1|FormalType=1|Electrical=4|PinConglomerate=35|PinLength=10|Location.X=200|Location.Y=550|Name=1|Designator=1|PinPropagationDelay=0.000000E+000
|RECORD=6|OwnerIndex=668|IsNotAccesible=T|IndexInSheet=2|OwnerPartId=1|LineWidth=1|Color=16711680|LocationCount=10|X1=200|Y1=570|X2=200|Y2=566|X3=202|Y3=565|X4=198|Y4=563|X5=202|Y5=561|X6=198|Y6=559|X7=202|Y7=557|X8=198|Y8=555|X9=200|Y9=554|X10=200|Y10=550
|RECORD=41|OwnerIndex=668|IndexInSheet=3|OwnerPartId=-1|Location.X=197|Location.Y=582|Color=8388608|FontID=1|IsHidden=T|Text=220 Ohm|Name=Resistance
|RECORD=41|OwnerIndex=668|IndexInSheet=4|OwnerPartId=-1|Location.X=197|Location.Y=582|Color=8388608|FontID=1|IsHidden=T|Text=0603|Name=PackageReference
|RECORD=41|OwnerIndex=668|IndexInSheet=5|OwnerPartId=-1|Location.X=197|Location.Y=582|Color=8388608|FontID=1|IsHidden=T|Text=50 V|Name=Voltage Rating
|RECORD=41|OwnerIndex=668|IndexInSheet=6|OwnerPartId=-1|Location.X=197|Location.Y=582|Color=8388608|FontID=1|IsHidden=T|Text=125 degC|Name=Max Operating Temperature
|RECORD=41|OwnerIndex=668|IndexInSheet=7|OwnerPartId=-1|Location.X=197|Location.Y=582|Color=8388608|FontID=1|IsHidden=T|Text=4|Name=Elements
|RECORD=41|OwnerIndex=668|IndexInSheet=8|OwnerPartId=-1|Location.X=197|Location.Y=582|Color=8388608|FontID=1|IsHidden=T|Text=No SVHC|Name=REACH SVHC
|RECORD=41|OwnerIndex=668|IndexInSheet=9|OwnerPartId=-1|Location.X=197|Location.Y=582|Color=8388608|FontID=1|IsHidden=T|Text=0.063 inch|Name=Width
|RECORD=41|OwnerIndex=668|IndexInSheet=10|OwnerPartId=-1|Location.X=197|Location.Y=582|Color=8388608|FontID=1|IsHidden=T|Text=1205|Name=Case\Package
|RECORD=41|OwnerIndex=668|IndexInSheet=11|OwnerPartId=-1|Location.X=197|Location.Y=582|Color=8388608|FontID=1|IsHidden=T|Text=0.126 inch|Name=Length
|RECORD=41|OwnerIndex=668|IndexInSheet=12|OwnerPartId=-1|Location.X=197|Location.Y=582|Color=8388608|FontID=1|IsHidden=T|Text=0.024 inch|Name=Height
|RECORD=41|OwnerIndex=668|IndexInSheet=13|OwnerPartId=-1|Location.X=197|Location.Y=582|Color=8388608|FontID=1|IsHidden=T|Text=Surface Mount|Name=Mount
|RECORD=41|OwnerIndex=668|IndexInSheet=14|OwnerPartId=-1|Location.X=197|Location.Y=582|Color=8388608|FontID=1|IsHidden=T|Text=1|Name=Package Quantity
|RECORD=41|OwnerIndex=668|IndexInSheet=15|OwnerPartId=-1|Location.X=197|Location.Y=582|Color=8388608|FontID=1|IsHidden=T|Text=Apr-15|Name=DatasheetVersion
|RECORD=41|OwnerIndex=668|IndexInSheet=16|OwnerPartId=-1|Location.X=197|Location.Y=582|Color=8388608|FontID=1|IsHidden=T|Text=Manufacturer URL|Name=ComponentLink1Description
|RECORD=41|OwnerIndex=668|IndexInSheet=17|OwnerPartId=-1|Location.X=197|Location.Y=582|Color=8388608|FontID=1|IsHidden=T|Text=-55 degC|Name=Min Operating Temperature
|RECORD=41|OwnerIndex=668|IndexInSheet=18|OwnerPartId=-1|Location.X=197|Location.Y=582|Color=8388608|FontID=1|IsHidden=T|Text=Tape and Reel|Name=Packaging
|RECORD=41|OwnerIndex=668|IndexInSheet=19|OwnerPartId=-1|Location.X=197|Location.Y=582|Color=8388608|FontID=1|IsHidden=T|Text=No|Name=Radiation Hardening
|RECORD=41|OwnerIndex=668|IndexInSheet=20|OwnerPartId=-1|Location.X=197|Location.Y=582|Color=8388608|FontID=2|IsHidden=T|Text=http://industrial.panasonic.com/cdbs/www-data/pdf/RDA0000/AOA0000C86.pdf|Name=ComponentLink2URL
|RECORD=41|OwnerIndex=668|IndexInSheet=21|OwnerPartId=-1|Location.X=197|Location.Y=582|Color=8388608|FontID=1|IsHidden=T|Text=3216|Name=Case Code (Metric)
|RECORD=41|OwnerIndex=668|IndexInSheet=22|OwnerPartId=-1|Location.X=197|Location.Y=582|Color=8388608|FontID=1|IsHidden=T|Text=8|Name=Pins
|RECORD=41|OwnerIndex=668|IndexInSheet=23|OwnerPartId=-1|Location.X=197|Location.Y=582|Color=8388608|FontID=1|IsHidden=T|Text=1206|Name=Case Code (Imperial)
|RECORD=41|OwnerIndex=668|IndexInSheet=24|OwnerPartId=-1|Location.X=197|Location.Y=582|Color=8388608|FontID=1|IsHidden=T|Text=Thick Film|Name=Type (Resistor)
|RECORD=41|OwnerIndex=668|IndexInSheet=25|OwnerPartId=-1|Location.X=197|Location.Y=582|Color=8388608|FontID=1|IsHidden=T|Text=true|Name=RoHSCompliant
|RECORD=41|OwnerIndex=668|IndexInSheet=26|OwnerPartId=-1|Location.X=197|Location.Y=582|Color=8388608|FontID=1|IsHidden=T|Text=5%|Name=Tolerance
|RECORD=41|OwnerIndex=668|IndexInSheet=27|OwnerPartId=-1|Location.X=197|Location.Y=582|Color=8388608|FontID=1|IsHidden=T|Text=Datasheet|Name=ComponentLink2Description
|RECORD=41|OwnerIndex=668|IndexInSheet=28|OwnerPartId=-1|Location.X=197|Location.Y=582|Color=8388608|FontID=1|IsHidden=T|Text=2-Pin Surface Mount Device, Body 1.6 x 0.85 mm|Name=PackageDescription
|RECORD=41|OwnerIndex=668|IndexInSheet=29|OwnerPartId=-1|Location.X=197|Location.Y=582|Color=8388608|FontID=2|IsHidden=T|Text=http://www.panasonic.com/|Name=ComponentLink1URL
|RECORD=41|OwnerIndex=668|IndexInSheet=30|OwnerPartId=-1|Location.X=197|Location.Y=582|Color=8388608|FontID=1|IsHidden=T|Text=250 mW|Name=Power Rating
|RECORD=34|OwnerIndex=668|IndexInSheet=-1|OwnerPartId=-1|Location.X=203|Location.Y=561|Color=8388608|FontID=1|Text=R26|Name=Designator|ReadOnlyState=1
|RECORD=41|OwnerIndex=668|IndexInSheet=-1|OwnerPartId=-1|Location.X=203|Location.Y=551|Color=8388608|FontID=1|Text=4.7K|Name=Comment
|RECORD=44|OwnerIndex=668
|RECORD=45|OwnerIndex=704|IndexInSheet=-1|Description=Chip Resistor, 2-Leads, Body 1.75x0.95mm, IPC Medium Density|UseComponentLibrary=T|ModelName=RESC1608X55X30NL15T15|ModelType=PCBLIB|IsCurrent=T|DatalinksLocked=T|DatabaseDatalinksLocked=T
|RECORD=46|OwnerIndex=705
|RECORD=48|OwnerIndex=705
|RECORD=41|OwnerIndex=707|IndexInSheet=-1|OwnerPartId=-1|Color=8388608|FontID=1|IsHidden=T|Text=2D|Name=Available Preview Images
|RECORD=45|OwnerIndex=704|IndexInSheet=-1|Description=Chip Resistor, 2-Leads, Body 1.75x0.95mm, IPC Low Density|UseComponentLibrary=T|ModelName=RESC1608X55X30ML15T15|ModelType=PCBLIB|DatalinksLocked=T|DatabaseDatalinksLocked=T
|RECORD=46|OwnerIndex=709
|RECORD=48|OwnerIndex=709
|RECORD=41|OwnerIndex=711|IndexInSheet=-1|OwnerPartId=-1|Color=8388608|FontID=1|IsHidden=T|Text=2D|Name=Available Preview Images
|RECORD=45|OwnerIndex=704|IndexInSheet=-1|Description=Chip Resistor, 2-Leads, Body 1.75x0.95mm, IPC High Density|UseComponentLibrary=T|ModelName=RESC1608X55X30LL15T15|ModelType=PCBLIB|DatalinksLocked=T|DatabaseDatalinksLocked=T
|RECORD=46|OwnerIndex=713
|RECORD=48|OwnerIndex=713
|RECORD=41|OwnerIndex=715|IndexInSheet=-1|OwnerPartId=-1|Color=8388608|FontID=1|IsHidden=T|Text=2D|Name=Available Preview Images
|RECORD=1|LibReference=Header 4|ComponentDescription=Header, 4-Pin|PartCount=2|DisplayModeCount=1|IndexInSheet=99|OwnerPartId=-1|Location.X=250|Location.Y=400|CurrentPartId=1|SourceLibraryName=Miscellaneous Connectors.IntLib|TargetFileName=*|AreaColor=11599871|Color=128|PartIDLocked=F|DesignItemId=Header 4|AllPinCount=4
|RECORD=14|OwnerIndex=717|IsNotAccesible=T|OwnerPartId=1|Location.X=250|Location.Y=350|Corner.X=280|Corner.Y=400|Color=128|AreaColor=11599871|IsSolid=T
|RECORD=2|OwnerIndex=717|OwnerPartId=1|FormalType=1|Electrical=4|PinConglomerate=42|PinLength=20|Location.X=250|Location.Y=390|Name=1|Designator=1|PinPropagationDelay=0.000000E+000
|RECORD=2|OwnerIndex=717|OwnerPartId=1|FormalType=1|Electrical=4|PinConglomerate=42|PinLength=20|Location.X=250|Location.Y=380|Name=2|Designator=2|PinPropagationDelay=0.000000E+000
|RECORD=2|OwnerIndex=717|OwnerPartId=1|FormalType=1|Electrical=4|PinConglomerate=42|PinLength=20|Location.X=250|Location.Y=370|Name=3|Designator=3|PinPropagationDelay=0.000000E+000
|RECORD=2|OwnerIndex=717|OwnerPartId=1|FormalType=1|Electrical=4|PinConglomerate=42|PinLength=20|Location.X=250|Location.Y=360|Name=4|Designator=4|PinPropagationDelay=0.000000E+000
|RECORD=41|OwnerIndex=717|IndexInSheet=5|OwnerPartId=-1|Location.X=250|Location.Y=400|Color=8388608|FontID=1|IsHidden=T|Text=17-Jul-2002|Name=LatestRevisionDate
|RECORD=41|OwnerIndex=717|IndexInSheet=6|OwnerPartId=-1|Location.X=250|Location.Y=400|Color=8388608|FontID=1|IsHidden=T|Text=Re-released for DXP Platform.|Name=LatestRevisionNote
|RECORD=41|OwnerIndex=717|IndexInSheet=7|OwnerPartId=-1|Location.X=250|Location.Y=400|Color=8388608|FontID=1|IsHidden=T|Text=Altium Limited|Name=Publisher
|RECORD=34|OwnerIndex=717|IndexInSheet=-1|OwnerPartId=-1|Location.X=250|Location.Y=400|Color=8388608|FontID=1|Text=P3|Name=Designator|ReadOnlyState=1
|RECORD=41|OwnerIndex=717|IndexInSheet=-1|OwnerPartId=-1|Location.X=250|Location.Y=340|Color=8388608|FontID=1|Text=AUX Sensor|Name=Comment|ReadOnlyState=1
|RECORD=44|OwnerIndex=717
|RECORD=45|OwnerIndex=732|IndexInSheet=-1|Description=Connector; Header; 4 Position|UseComponentLibrary=T|ModelName=HDR1X4|ModelType=PCBLIB|DatafileCount=1|ModelDatafileEntity0=HDR1X4|ModelDatafileKind0=PCBLib|IsCurrent=T|DatalinksLocked=T|DatabaseDatalinksLocked=T|IntegratedModel=T|DatabaseModel=T
|RECORD=46|OwnerIndex=733
|RECORD=48|OwnerIndex=733
|RECORD=45|OwnerIndex=732|IndexInSheet=-1|UseComponentLibrary=T|ModelName=Connector|ModelType=SI|IsCurrent=T|DatalinksLocked=T|DatabaseDatalinksLocked=T|IntegratedModel=T|DatabaseModel=T
|RECORD=46|OwnerIndex=736
|RECORD=48|OwnerIndex=736
|RECORD=41|OwnerIndex=738|IndexInSheet=-1|OwnerPartId=-1|Color=8388608|FontID=1|Text=Connector|Name=Type
|RECORD=41|OwnerIndex=738|IndexInSheet=-1|OwnerPartId=-1|Color=8388608|FontID=1|Name=Tech
|RECORD=17|IndexInSheet=100|OwnerPartId=-1|ShowNetName=T|Location.X=170|Location.Y=420|Orientation=1|Color=128|FontID=1|Text=+3.3V
|RECORD=17|IndexInSheet=101|OwnerPartId=-1|Style=4|ShowNetName=T|Location.X=180|Location.Y=350|Orientation=3|Color=128|FontID=1|Text=GND
|RECORD=17|IndexInSheet=102|OwnerPartId=-1|ShowNetName=T|Location.X=160|Location.Y=360|Orientation=2|Color=255|FontID=1|Text=SDA|IsCrossSheetConnector=T
|RECORD=17|IndexInSheet=103|OwnerPartId=-1|ShowNetName=T|Location.X=160|Location.Y=370|Orientation=2|Color=255|FontID=1|Text=SCL|IsCrossSheetConnector=T
|RECORD=27|IndexInSheet=104|OwnerPartId=-1|LineWidth=1|Color=8388608|LocationCount=4|X1=270|Y1=770|X2=270|Y2=760|X3=220|Y3=760|X4=220|Y4=770
|RECORD=27|IndexInSheet=105|OwnerPartId=-1|LineWidth=1|Color=8388608|LocationCount=4|X1=220|Y1=800|X2=220|Y2=810|X3=270|Y3=810|X4=560|Y4=810
|RECORD=27|IndexInSheet=106|OwnerPartId=-1|LineWidth=1|Color=8388608|LocationCount=4|X1=370|Y1=770|X2=370|Y2=760|X3=320|Y3=760|X4=320|Y4=770
|RECORD=27|IndexInSheet=107|OwnerPartId=-1|LineWidth=1|Color=8388608|LocationCount=4|X1=320|Y1=840|X2=320|Y2=820|X3=370|Y3=820|X4=560|Y4=820
|RECORD=27|IndexInSheet=108|OwnerPartId=-1|LineWidth=1|Color=8388608|LocationCount=2|X1=560|Y1=790|X2=470|Y2=790
|RECORD=27|IndexInSheet=109|OwnerPartId=-1|LineWidth=1|Color=8388608|LocationCount=2|X1=560|Y1=800|X2=470|Y2=800
|RECORD=27|IndexInSheet=110|OwnerPartId=-1|LineWidth=1|Color=8388608|LocationCount=2|X1=810|Y1=790|X2=720|Y2=790
|RECORD=27|IndexInSheet=111|OwnerPartId=-1|LineWidth=1|Color=8388608|LocationCount=2|X1=810|Y1=800|X2=720|Y2=800
|RECORD=27|IndexInSheet=112|OwnerPartId=-1|LineWidth=1|Color=8388608|LocationCount=2|X1=810|Y1=810|X2=720|Y2=810
|RECORD=27|IndexInSheet=113|OwnerPartId=-1|LineWidth=1|Color=8388608|LocationCount=3|X1=720|Y1=820|X2=740|Y2=820|X3=740|Y3=750
|RECORD=27|IndexInSheet=114|OwnerPartId=-1|LineWidth=1|Color=8388608|LocationCount=2|X1=220|Y1=840|X2=220|Y2=810
|RECORD=27|IndexInSheet=115|OwnerPartId=-1|LineWidth=1|Color=8388608|LocationCount=2|X1=270|Y1=800|X2=270|Y2=810
|RECORD=27|IndexInSheet=116|OwnerPartId=-1|LineWidth=1|Color=8388608|LocationCount=2|X1=320|Y1=820|X2=320|Y2=800
|RECORD=27|IndexInSheet=117|OwnerPartId=-1|LineWidth=1|Color=8388608|LocationCount=2|X1=370|Y1=800|X2=370|Y2=820
|RECORD=27|IndexInSheet=118|OwnerPartId=-1|LineWidth=1|Color=8388608|LocationCount=2|X1=1390|Y1=840|X2=1310|Y2=840
|RECORD=27|IndexInSheet=119|OwnerPartId=-1|LineWidth=1|Color=8388608|LocationCount=2|X1=1310|Y1=830|X2=1390|Y2=830
|RECORD=27|IndexInSheet=120|OwnerPartId=-1|LineWidth=1|Color=8388608|LocationCount=3|X1=1310|Y1=800|X2=1350|Y2=800|X3=1350|Y3=740
|RECORD=27|IndexInSheet=121|OwnerPartId=-1|LineWidth=1|Color=8388608|LocationCount=3|X1=1200|Y1=840|X2=1160|Y2=840|X3=1160|Y3=890
|RECORD=27|IndexInSheet=122|OwnerPartId=-1|LineWidth=1|Color=8388608|LocationCount=2|X1=1160|Y1=840|X2=1160|Y2=780
|RECORD=27|IndexInSheet=123|OwnerPartId=-1|LineWidth=1|Color=8388608|LocationCount=2|X1=1110|Y1=890|X2=1110|Y2=870
|RECORD=27|IndexInSheet=124|OwnerPartId=-1|LineWidth=1|Color=8388608|LocationCount=3|X1=1200|Y1=800|X2=1110|Y2=800|X3=1110|Y3=830
|RECORD=27|IndexInSheet=125|OwnerPartId=-1|LineWidth=1|Color=8388608|LocationCount=2|X1=1160|Y1=750|X2=1160|Y2=740
|RECORD=27|IndexInSheet=126|OwnerPartId=-1|LineWidth=1|Color=8388608|LocationCount=2|X1=1110|Y1=800|X2=1090|Y2=800
|RECORD=27|IndexInSheet=127|OwnerPartId=-1|LineWidth=1|Color=8388608|LocationCount=3|X1=1130|Y1=430|X2=1090|Y2=430|X3=1090|Y3=490
|RECORD=27|IndexInSheet=128|OwnerPartId=-1|LineWidth=1|Color=8388608|LocationCount=3|X1=1130|Y1=420|X2=1040|Y2=420|X3=1040|Y3=490
|RECORD=27|IndexInSheet=129|OwnerPartId=-1|LineWidth=1|Color=8388608|LocationCount=2|X1=1040|Y1=420|X2=1040|Y2=320
|RECORD=27|IndexInSheet=130|OwnerPartId=-1|LineWidth=1|Color=8388608|LocationCount=2|X1=1090|Y1=320|X2=1090|Y2=430
|RECORD=27|IndexInSheet=131|OwnerPartId=-1|LineWidth=1|Color=8388608|LocationCount=2|X1=1040|Y1=290|X2=1040|Y2=270
|RECORD=27|IndexInSheet=132|OwnerPartId=-1|LineWidth=1|Color=8388608|LocationCount=2|X1=1090|Y1=290|X2=1090|Y2=270
|RECORD=27|IndexInSheet=133|OwnerPartId=-1|LineWidth=1|Color=8388608|LocationCount=6|X1=1290|Y1=370|X2=1350|Y2=370|X3=1350|Y3=360|X4=1350|Y4=350|X5=1350|Y5=340|X6=1350|Y6=270
|RECORD=27|IndexInSheet=134|OwnerPartId=-1|LineWidth=1|Color=8388608|LocationCount=2|X1=1290|Y1=360|X2=1350|Y2=360
|RECORD=27|IndexInSheet=135|OwnerPartId=-1|LineWidth=1|Color=8388608|LocationCount=2|X1=1290|Y1=350|X2=1350|Y2=350
|RECORD=27|IndexInSheet=136|OwnerPartId=-1|LineWidth=1|Color=8388608|LocationCount=2|X1=1290|Y1=340|X2=1350|Y2=340
|RECORD=27|IndexInSheet=137|OwnerPartId=-1|LineWidth=1|Color=8388608|LocationCount=2|X1=1290|Y1=390|X2=1420|Y2=390
|RECORD=27|IndexInSheet=138|OwnerPartId=-1|LineWidth=1|Color=8388608|LocationCount=2|X1=1130|Y1=380|X2=1010|Y2=380
|RECORD=27|IndexInSheet=139|OwnerPartId=-1|LineWidth=1|Color=8388608|LocationCount=3|X1=1130|Y1=400|X2=1000|Y2=400|X3=1000|Y3=490
|RECORD=27|IndexInSheet=140|OwnerPartId=-1|LineWidth=1|Color=8388608|LocationCount=3|X1=1290|Y1=400|X2=1390|Y2=400|X3=1390|Y3=270
|RECORD=27|IndexInSheet=141|OwnerPartId=-1|LineWidth=1|Color=8388608|LocationCount=2|X1=440|Y1=290|X2=440|Y2=270
|RECORD=27|IndexInSheet=142|OwnerPartId=-1|LineWidth=1|Color=8388608|LocationCount=2|X1=390|Y1=290|X2=390|Y2=270
|RECORD=27|IndexInSheet=143|OwnerPartId=-1|LineWidth=1|Color=8388608|LocationCount=3|X1=470|Y1=410|X2=440|Y2=410|X3=440|Y3=320
|RECORD=27|IndexInSheet=144|OwnerPartId=-1|LineWidth=1|Color=8388608|LocationCount=3|X1=470|Y1=420|X2=390|Y2=420|X3=390|Y3=320
|RECORD=27|IndexInSheet=145|OwnerPartId=-1|LineWidth=1|Color=8388608|LocationCount=2|X1=440|Y1=410|X2=440|Y2=470
|RECORD=27|IndexInSheet=146|OwnerPartId=-1|LineWidth=1|Color=8388608|LocationCount=2|X1=390|Y1=420|X2=390|Y2=470
|RECORD=27|IndexInSheet=147|OwnerPartId=-1|LineWidth=1|Color=8388608|LocationCount=2|X1=610|Y1=410|X2=690|Y2=410
|RECORD=27|IndexInSheet=148|OwnerPartId=-1|LineWidth=1|Color=8388608|LocationCount=2|X1=610|Y1=420|X2=690|Y2=420
|RECORD=27|IndexInSheet=149|OwnerPartId=-1|LineWidth=1|Color=8388608|LocationCount=3|X1=610|Y1=390|X2=650|Y2=390|X3=650|Y3=470
|RECORD=27|IndexInSheet=150|OwnerPartId=-1|LineWidth=1|Color=8388608|LocationCount=4|X1=610|Y1=370|X2=650|Y2=370|X3=650|Y3=360|X4=650|Y4=270
|RECORD=27|IndexInSheet=151|OwnerPartId=-1|LineWidth=1|Color=8388608|LocationCount=3|X1=610|Y1=400|X2=690|Y2=400|X3=690|Y3=270
|RECORD=27|IndexInSheet=152|OwnerPartId=-1|LineWidth=1|Color=8388608|LocationCount=2|X1=610|Y1=360|X2=650|Y2=360
|RECORD=27|IndexInSheet=153|OwnerPartId=-1|LineWidth=1|Color=8388608|LocationCount=2|X1=200|Y1=610|X2=200|Y2=580
|RECORD=27|IndexInSheet=154|OwnerPartId=-1|LineWidth=1|Color=8388608|LocationCount=2|X1=250|Y1=610|X2=250|Y2=580
|RECORD=27|IndexInSheet=155|OwnerPartId=-1|LineWidth=1|Color=8388608|LocationCount=2|X1=250|Y1=540|X2=250|Y2=500
|RECORD=27|IndexInSheet=156|OwnerPartId=-1|LineWidth=1|Color=8388608|LocationCount=2|X1=200|Y1=540|X2=200|Y2=500
|RECORD=27|IndexInSheet=157|OwnerPartId=-1|LineWidth=1|Color=8388608|LocationCount=3|X1=230|Y1=390|X2=180|Y2=390|X3=180|Y3=350
|RECORD=27|IndexInSheet=158|OwnerPartId=-1|LineWidth=1|Color=8388608|LocationCount=3|X1=230|Y1=380|X2=170|Y2=380|X3=170|Y3=420
|RECORD=27|IndexInSheet=159|OwnerPartId=-1|LineWidth=1|Color=8388608|LocationCount=2|X1=230|Y1=370|X2=160|Y2=370
|RECORD=27|IndexInSheet=160|OwnerPartId=-1|LineWidth=1|Color=8388608|LocationCount=2|X1=230|Y1=360|X2=160|Y2=360
|RECORD=29|IndexInSheet=-1|OwnerPartId=-1|Location.X=220|Location.Y=760|Color=128
|RECORD=29|IndexInSheet=-1|OwnerPartId=-1|Location.X=220|Location.Y=810|Color=128
|RECORD=29|IndexInSheet=-1|OwnerPartId=-1|Location.X=270|Location.Y=810|Color=128
|RECORD=29|IndexInSheet=-1|OwnerPartId=-1|Location.X=320|Location.Y=760|Color=128
|RECORD=29|IndexInSheet=-1|OwnerPartId=-1|Location.X=320|Location.Y=820|Color=128
|RECORD=29|IndexInSheet=-1|OwnerPartId=-1|Location.X=370|Location.Y=820|Color=128
|RECORD=29|IndexInSheet=-1|OwnerPartId=-1|Location.X=390|Location.Y=420|Color=128
|RECORD=29|IndexInSheet=-1|OwnerPartId=-1|Location.X=440|Location.Y=410|Color=128
|RECORD=29|IndexInSheet=-1|OwnerPartId=-1|Location.X=650|Location.Y=360|Color=128
|RECORD=29|IndexInSheet=-1|OwnerPartId=-1|Location.X=1040|Location.Y=420|Color=128
|RECORD=29|IndexInSheet=-1|OwnerPartId=-1|Location.X=1090|Location.Y=430|Color=128
|RECORD=29|IndexInSheet=-1|OwnerPartId=-1|Location.X=1110|Location.Y=800|Color=128
|RECORD=29|IndexInSheet=-1|OwnerPartId=-1|Location.X=1160|Location.Y=840|Color=128
|RECORD=29|IndexInSheet=-1|OwnerPartId=-1|Location.X=1350|Location.Y=340|Color=128
|RECORD=29|IndexInSheet=-1|OwnerPartId=-1|Location.X=1350|Location.Y=350|Color=128
|RECORD=29|IndexInSheet=-1|OwnerPartId=-1|Location.X=1350|Location.Y=360|Color=128